{ Packager-XL run on 05-Sep-2022 AT 15:23:30 }
FILE_TYPE = BACK_ANNOTATION;
DRAWING = "@timecard_lib.timecard(sch_1):page3";
BODY = "CAPACITOR","I4": LOCATION = "C37" #&CDS_LOCATION = "C37" &SEC = "1" #&CDS_SEC = "1";
"1":   PN = "1"  !CDS_PN = "1";
"2":   PN = "2"  !CDS_PN = "2";
BODY = "RESISTOR","I15": LOCATION = "R23" #&CDS_LOCATION = "R23" &SEC = "1" #&CDS_SEC = "1";
"1":   PN = "1"  !CDS_PN = "1";
"2":   PN = "2"  !CDS_PN = "2";
BODY = "RESISTOR","I16": LOCATION = "R22" #&CDS_LOCATION = "R22" &SEC = "1" #&CDS_SEC = "1";
"1":   PN = "1"  !CDS_PN = "1";
"2":   PN = "2"  !CDS_PN = "2";
BODY = "CAPACITOR","I35": LOCATION = "C24" #&CDS_LOCATION = "C24" &SEC = "1" #&CDS_SEC = "1";
"1":   PN = "1"  !CDS_PN = "1";
"2":   PN = "2"  !CDS_PN = "2";
BODY = "CAPACITOR","I36": LOCATION = "C19" #&CDS_LOCATION = "C19" &SEC = "1" #&CDS_SEC = "1";
"1":   PN = "1"  !CDS_PN = "1";
"2":   PN = "2"  !CDS_PN = "2";
BODY = "CAPACITOR","I37": LOCATION = "C23" #&CDS_LOCATION = "C23" &SEC = "1" #&CDS_SEC = "1";
"1":   PN = "1"  !CDS_PN = "1";
"2":   PN = "2"  !CDS_PN = "2";
BODY = "RESISTOR","I51": LOCATION = "R43" #&CDS_LOCATION = "R43" &SEC = "1" #&CDS_SEC = "1";
"1":   PN = "1"  !CDS_PN = "1";
"2":   PN = "2"  !CDS_PN = "2";
BODY = "RESISTOR","I52": LOCATION = "R42" #&CDS_LOCATION = "R42" &SEC = "1" #&CDS_SEC = "1";
"1":   PN = "1"  !CDS_PN = "1";
"2":   PN = "2"  !CDS_PN = "2";
BODY = "RESISTOR","I53": LOCATION = "R41" #&CDS_LOCATION = "R41" &SEC = "1" #&CDS_SEC = "1";
"1":   PN = "1"  !CDS_PN = "1";
"2":   PN = "2"  !CDS_PN = "2";
BODY = "RESISTOR","I54": LOCATION = "R28" #&CDS_LOCATION = "R28" &SEC = "1" #&CDS_SEC = "1";
"1":   PN = "1"  !CDS_PN = "1";
"2":   PN = "2"  !CDS_PN = "2";
BODY = "CONN_64P_GF","I61": LOCATION = "GF1" #&CDS_LOCATION = "GF1" &SEC = "1" #&CDS_SEC = "1";
"GND1":   PN = "B4"  !CDS_PN = "B4";
"GND2":   PN = "A4"  !CDS_PN = "A4";
"GND3":   PN = "B7"  !CDS_PN = "B7";
"GND4":   PN = "A12"  !CDS_PN = "A12";
"GND5":   PN = "B13"  !CDS_PN = "B13";
"GND6":   PN = "A15"  !CDS_PN = "A15";
"GND7":   PN = "B16"  !CDS_PN = "B16";
"GND8":   PN = "A18"  !CDS_PN = "A18";
"GND9":   PN = "B18"  !CDS_PN = "B18";
"GND10":   PN = "A20"  !CDS_PN = "A20";
"GND11":   PN = "B21"  !CDS_PN = "B21";
"GND12":   PN = "B22"  !CDS_PN = "B22";
"GND13":   PN = "A23"  !CDS_PN = "A23";
"GND14":   PN = "A24"  !CDS_PN = "A24";
"GND15":   PN = "B25"  !CDS_PN = "B25";
"GND17":   PN = "B26"  !CDS_PN = "B26";
"GND18":   PN = "A27"  !CDS_PN = "A27";
"GND19":   PN = "A28"  !CDS_PN = "A28";
"GND20":   PN = "B29"  !CDS_PN = "B29";
"GND21":   PN = "A31"  !CDS_PN = "A31";
"GND22":   PN = "B32"  !CDS_PN = "B32";
"JTAG1":   PN = "B9"  !CDS_PN = "B9";
"JTAG2":   PN = "A5"  !CDS_PN = "A5";
"JTAG3":   PN = "A6"  !CDS_PN = "A6";
"JTAG4":   PN = "A7"  !CDS_PN = "A7";
"JTAG5":   PN = "A8"  !CDS_PN = "A8";
"P_3V3_1":   PN = "B8"  !CDS_PN = "B8";
"P_3V3_2":   PN = "A9"  !CDS_PN = "A9";
"P_3V3_3":   PN = "A10"  !CDS_PN = "A10";
"P_3V3AUX":   PN = "B10"  !CDS_PN = "B10";
"P_12V1":   PN = "B1"  !CDS_PN = "B1";
"P_12V2":   PN = "B2"  !CDS_PN = "B2";
"P_12V3":   PN = "A2"  !CDS_PN = "A2";
"P_12V4":   PN = "B3"  !CDS_PN = "B3";
"P_12V5":   PN = "A3"  !CDS_PN = "A3";
"PERN0":   PN = "A17"  !CDS_PN = "A17";
"PERN1":   PN = "A22"  !CDS_PN = "A22";
"PERN2":   PN = "A26"  !CDS_PN = "A26";
"PERN3":   PN = "A30"  !CDS_PN = "A30";
"PERP0":   PN = "A16"  !CDS_PN = "A16";
"PERP1":   PN = "A21"  !CDS_PN = "A21";
"PERP2":   PN = "A25"  !CDS_PN = "A25";
"PERP3":   PN = "A29"  !CDS_PN = "A29";
"PERST*":   PN = "A11"  !CDS_PN = "A11";
"PETN0":   PN = "B15"  !CDS_PN = "B15";
"PETN1":   PN = "B20"  !CDS_PN = "B20";
"PETN2":   PN = "B24"  !CDS_PN = "B24";
"PETN3":   PN = "B28"  !CDS_PN = "B28";
"PETP0":   PN = "B14"  !CDS_PN = "B14";
"PETP1":   PN = "B19"  !CDS_PN = "B19";
"PETP2":   PN = "B23"  !CDS_PN = "B23";
"PETP3":   PN = "B27"  !CDS_PN = "B27";
"PRSNT1*":   PN = "A1"  !CDS_PN = "A1";
"PRSNT2_1*":   PN = "B17"  !CDS_PN = "B17";
"PRSNT2_2*":   PN = "B31"  !CDS_PN = "B31";
"REFCLK_N":   PN = "A14"  !CDS_PN = "A14";
"REFCLK_P":   PN = "A13"  !CDS_PN = "A13";
"RSVD1":   PN = "B12"  !CDS_PN = "B12";
"RSVD2":   PN = "A19"  !CDS_PN = "A19";
"RSVD3":   PN = "B30"  !CDS_PN = "B30";
"RSVD4":   PN = "A32"  !CDS_PN = "A32";
"SMCLK":   PN = "B5"  !CDS_PN = "B5";
"SMDAT":   PN = "B6"  !CDS_PN = "B6";
"WAKE*":   PN = "B11"  !CDS_PN = "B11";
BODY = "RESISTOR","I62": LOCATION = "R55" #&CDS_LOCATION = "R55" &SEC = "1" #&CDS_SEC = "1";
"1":   PN = "1"  !CDS_PN = "1";
"2":   PN = "2"  !CDS_PN = "2";
BODY = "RESISTOR","I63": LOCATION = "R56" #&CDS_LOCATION = "R56" &SEC = "1" #&CDS_SEC = "1";
"1":   PN = "1"  !CDS_PN = "1";
"2":   PN = "2"  !CDS_PN = "2";
BODY = "CAPACITOR","I92": LOCATION = "C17" #&CDS_LOCATION = "C17" &SEC = "1" #&CDS_SEC = "1";
"1":   PN = "1"  !CDS_PN = "1";
"2":   PN = "2"  !CDS_PN = "2";
BODY = "G220_10198_01","I100": LOCATION = "U2" #&CDS_LOCATION = "U2" &SEC = "1" #&CDS_SEC = "1";
"EN":   PN = "1"  !CDS_PN = "1";
"GND":   PN = "4"  !CDS_PN = "4";
"READY":   PN = "5"  !CDS_PN = "5";
"SCLIN":   PN = "3"  !CDS_PN = "3";
"SCLOUT":   PN = "2"  !CDS_PN = "2";
"SDAIN":   PN = "6"  !CDS_PN = "6";
"SDAOUT":   PN = "7"  !CDS_PN = "7";
"VCC":   PN = "8"  !CDS_PN = "8";
BODY = "RESISTOR","I103": LOCATION = "R25" #&CDS_LOCATION = "R25" &SEC = "1" #&CDS_SEC = "1";
"1":   PN = "1"  !CDS_PN = "1";
"2":   PN = "2"  !CDS_PN = "2";
BODY = "RESISTOR","I114": LOCATION = "R354" #&CDS_LOCATION = "R354" &SEC = "1" #&CDS_SEC = "1";
"1":   PN = "1"  !CDS_PN = "1";
"2":   PN = "2"  !CDS_PN = "2";
BODY = "CAPACITOR","I115": #LOCATION = "C25" !CDS_LOCATION = "C25" &SEC = "1" #&CDS_SEC = "1";
"1":   PN = "1"  !CDS_PN = "1";
"2":   PN = "2"  !CDS_PN = "2";
BODY = "CAPACITOR","I116": #LOCATION = "C26" !CDS_LOCATION = "C26" &SEC = "1" #&CDS_SEC = "1";
"1":   PN = "1"  !CDS_PN = "1";
"2":   PN = "2"  !CDS_PN = "2";
BODY = "CAPACITOR","I117": #LOCATION = "C27" !CDS_LOCATION = "C27" &SEC = "1" #&CDS_SEC = "1";
"1":   PN = "1"  !CDS_PN = "1";
"2":   PN = "2"  !CDS_PN = "2";
BODY = "CAPACITOR","I118": #LOCATION = "C28" !CDS_LOCATION = "C28" &SEC = "1" #&CDS_SEC = "1";
"1":   PN = "1"  !CDS_PN = "1";
"2":   PN = "2"  !CDS_PN = "2";
BODY = "CAPACITOR","I119": #LOCATION = "C34" !CDS_LOCATION = "C34" &SEC = "1" #&CDS_SEC = "1";
"1":   PN = "1"  !CDS_PN = "1";
"2":   PN = "2"  !CDS_PN = "2";
BODY = "CAPACITOR","I120": #LOCATION = "C35" !CDS_LOCATION = "C35" &SEC = "1" #&CDS_SEC = "1";
"1":   PN = "1"  !CDS_PN = "1";
"2":   PN = "2"  !CDS_PN = "2";
BODY = "CAPACITOR","I121": #LOCATION = "C36" !CDS_LOCATION = "C36" &SEC = "1" #&CDS_SEC = "1";
"1":   PN = "1"  !CDS_PN = "1";
"2":   PN = "2"  !CDS_PN = "2";
BODY = "RESISTOR","I122": LOCATION = "R356" #&CDS_LOCATION = "R356" &SEC = "1" #&CDS_SEC = "1";
"1":   PN = "1"  !CDS_PN = "1";
"2":   PN = "2"  !CDS_PN = "2";
BODY = "CAPACITOR","I124": LOCATION = "C289" #&CDS_LOCATION = "C289" &SEC = "1" #&CDS_SEC = "1";
"1":   PN = "1"  !CDS_PN = "1";
"2":   PN = "2"  !CDS_PN = "2";
BODY = "CAPACITOR","I126": LOCATION = "C290" #&CDS_LOCATION = "C290" &SEC = "1" #&CDS_SEC = "1";
"1":   PN = "1"  !CDS_PN = "1";
"2":   PN = "2"  !CDS_PN = "2";
BODY = "CAPACITOR","I127": LOCATION = "C288" #&CDS_LOCATION = "C288" &SEC = "1" #&CDS_SEC = "1";
"1":   PN = "1"  !CDS_PN = "1";
"2":   PN = "2"  !CDS_PN = "2";
BODY = "CAPACITOR","I129": LOCATION = "C287" #&CDS_LOCATION = "C287" &SEC = "1" #&CDS_SEC = "1";
"1":   PN = "1"  !CDS_PN = "1";
"2":   PN = "2"  !CDS_PN = "2";
BODY = "FERRITEBEAD","I132": LOCATION = "L21" #&CDS_LOCATION = "L21" &SEC = "1" #&CDS_SEC = "1";
"1":   PN = "1"  !CDS_PN = "1";
"2":   PN = "2"  !CDS_PN = "2";
BODY = "74LVC1G07_SC70_5","I134": #LOCATION = "U3" !CDS_LOCATION = "U3" &SEC = "1" #&CDS_SEC = "1";
"A":   PN = "2"  !CDS_PN = "2";
"NC":   PN = "1"  !CDS_PN = "1";
"Y":   PN = "4"  !CDS_PN = "4";
BODY = "74LVC1G07_SC70_5","I135": #LOCATION = "U3" !CDS_LOCATION = "U3" &SEC = "2" #&CDS_SEC = "2";
"GND":   PN = "3"  !CDS_PN = "3";
"VCC":   PN = "5"  !CDS_PN = "5";
BODY = "TPS3808G18DBVR_SOT23_6","I139": LOCATION = "U34" #&CDS_LOCATION = "U34" &SEC = "1" #&CDS_SEC = "1";
"CT":   PN = "4"  !CDS_PN = "4";
"GND":   PN = "2"  !CDS_PN = "2";
"MR*":   PN = "3"  !CDS_PN = "3";
"RESET*":   PN = "1"  !CDS_PN = "1";
"SENSE":   PN = "5"  !CDS_PN = "5";
"VDD":   PN = "6"  !CDS_PN = "6";
BODY = "RESISTOR","I144": LOCATION = "R63" #&CDS_LOCATION = "R63" &SEC = "1" #&CDS_SEC = "1";
"1":   PN = "1"  !CDS_PN = "1";
"2":   PN = "2"  !CDS_PN = "2";
BODY = "RESISTOR","I148": LOCATION = "R167" #&CDS_LOCATION = "R167" &SEC = "1" #&CDS_SEC = "1";
"1":   PN = "1"  !CDS_PN = "1";
"2":   PN = "2"  !CDS_PN = "2";
BODY = "RESISTOR","I151": LOCATION = "R164" #&CDS_LOCATION = "R164" &SEC = "1" #&CDS_SEC = "1";
"1":   PN = "1"  !CDS_PN = "1";
"2":   PN = "2"  !CDS_PN = "2";
BODY = "CAPACITOR","I152": LOCATION = "C250" #&CDS_LOCATION = "C250" &SEC = "1" #&CDS_SEC = "1";
"1":   PN = "1"  !CDS_PN = "1";
"2":   PN = "2"  !CDS_PN = "2";
BODY = "RESISTOR","I153": LOCATION = "R57" #&CDS_LOCATION = "R57" &SEC = "1" #&CDS_SEC = "1";
"1":   PN = "1"  !CDS_PN = "1";
"2":   PN = "2"  !CDS_PN = "2";
DRAWING = "@timecard_lib.timecard(sch_1):page5";
BODY = "RESISTOR","I4": LOCATION = "R59" #&CDS_LOCATION = "R59" &SEC = "1" #&CDS_SEC = "1";
"1":   PN = "1"  !CDS_PN = "1";
"2":   PN = "2"  !CDS_PN = "2";
BODY = "PCA9546APW_TSSOP16","I33": LOCATION = "U4" #&CDS_LOCATION = "U4" &SEC = "1" #&CDS_SEC = "1";
"A0":   PN = "1"  !CDS_PN = "1";
"A1":   PN = "2"  !CDS_PN = "2";
"A2":   PN = "13"  !CDS_PN = "13";
"RESET*":   PN = "3"  !CDS_PN = "3";
"SC0":   PN = "5"  !CDS_PN = "5";
"SC1":   PN = "7"  !CDS_PN = "7";
"SC2":   PN = "10"  !CDS_PN = "10";
"SC3":   PN = "12"  !CDS_PN = "12";
"SCL":   PN = "14"  !CDS_PN = "14";
"SD0":   PN = "4"  !CDS_PN = "4";
"SD1":   PN = "6"  !CDS_PN = "6";
"SD2":   PN = "9"  !CDS_PN = "9";
"SD3":   PN = "11"  !CDS_PN = "11";
"SDA":   PN = "15"  !CDS_PN = "15";
BODY = "CAPACITOR","I45": LOCATION = "C38" #&CDS_LOCATION = "C38" &SEC = "1" #&CDS_SEC = "1";
"1":   PN = "1"  !CDS_PN = "1";
"2":   PN = "2"  !CDS_PN = "2";
BODY = "RESISTOR","I52": LOCATION = "R61" #&CDS_LOCATION = "R61" &SEC = "1" #&CDS_SEC = "1";
"1":   PN = "1"  !CDS_PN = "1";
"2":   PN = "2"  !CDS_PN = "2";
BODY = "PCA9546APW_TSSOP16","I54": LOCATION = "U4" #&CDS_LOCATION = "U4" &SEC = "2" #&CDS_SEC = "2";
"VDD":   PN = "16"  !CDS_PN = "16";
"VSS":   PN = "8"  !CDS_PN = "8";
BODY = "RESISTOR","I55": LOCATION = "R62" #&CDS_LOCATION = "R62" &SEC = "1" #&CDS_SEC = "1";
"1":   PN = "1"  !CDS_PN = "1";
"2":   PN = "2"  !CDS_PN = "2";
BODY = "RESISTOR","I60": LOCATION = "R146" #&CDS_LOCATION = "R146" &SEC = "1" #&CDS_SEC = "1";
"1":   PN = "1"  !CDS_PN = "1";
"2":   PN = "2"  !CDS_PN = "2";
BODY = "RESISTOR","I66": LOCATION = "R155" #&CDS_LOCATION = "R155" &SEC = "1" #&CDS_SEC = "1";
"1":   PN = "1"  !CDS_PN = "1";
"2":   PN = "2"  !CDS_PN = "2";
BODY = "RESISTOR","I67": LOCATION = "R145" #&CDS_LOCATION = "R145" &SEC = "1" #&CDS_SEC = "1";
"1":   PN = "1"  !CDS_PN = "1";
"2":   PN = "2"  !CDS_PN = "2";
BODY = "RESISTOR","I68": LOCATION = "R144" #&CDS_LOCATION = "R144" &SEC = "1" #&CDS_SEC = "1";
"1":   PN = "1"  !CDS_PN = "1";
"2":   PN = "2"  !CDS_PN = "2";
BODY = "RESISTOR","I69": LOCATION = "R26" #&CDS_LOCATION = "R26" &SEC = "1" #&CDS_SEC = "1";
"1":   PN = "1"  !CDS_PN = "1";
"2":   PN = "2"  !CDS_PN = "2";
BODY = "RESISTOR","I72": LOCATION = "R27" #&CDS_LOCATION = "R27" &SEC = "1" #&CDS_SEC = "1";
"1":   PN = "1"  !CDS_PN = "1";
"2":   PN = "2"  !CDS_PN = "2";
BODY = "RESISTOR","I80": #LOCATION = "R147" !CDS_LOCATION = "R147" &SEC = "1" #&CDS_SEC = "1";
"1":   PN = "1"  !CDS_PN = "1";
"2":   PN = "2"  !CDS_PN = "2";
BODY = "RESISTOR","I81": #LOCATION = "R148" !CDS_LOCATION = "R148" &SEC = "1" #&CDS_SEC = "1";
"1":   PN = "1"  !CDS_PN = "1";
"2":   PN = "2"  !CDS_PN = "2";
BODY = "RESISTOR","I82": #LOCATION = "R149" !CDS_LOCATION = "R149" &SEC = "1" #&CDS_SEC = "1";
"1":   PN = "1"  !CDS_PN = "1";
"2":   PN = "2"  !CDS_PN = "2";
BODY = "RESISTOR","I83": #LOCATION = "R150" !CDS_LOCATION = "R150" &SEC = "1" #&CDS_SEC = "1";
"1":   PN = "1"  !CDS_PN = "1";
"2":   PN = "2"  !CDS_PN = "2";
BODY = "RESISTOR","I84": #LOCATION = "R151" !CDS_LOCATION = "R151" &SEC = "1" #&CDS_SEC = "1";
"1":   PN = "1"  !CDS_PN = "1";
"2":   PN = "2"  !CDS_PN = "2";
BODY = "RESISTOR","I85": #LOCATION = "R152" !CDS_LOCATION = "R152" &SEC = "1" #&CDS_SEC = "1";
"1":   PN = "1"  !CDS_PN = "1";
"2":   PN = "2"  !CDS_PN = "2";
BODY = "RESISTOR","I86": #LOCATION = "R153" !CDS_LOCATION = "R153" &SEC = "1" #&CDS_SEC = "1";
"1":   PN = "1"  !CDS_PN = "1";
"2":   PN = "2"  !CDS_PN = "2";
BODY = "RESISTOR","I87": #LOCATION = "R154" !CDS_LOCATION = "R154" &SEC = "1" #&CDS_SEC = "1";
"1":   PN = "1"  !CDS_PN = "1";
"2":   PN = "2"  !CDS_PN = "2";
BODY = "RESISTOR","I88": #LOCATION = "R58" !CDS_LOCATION = "R58" &SEC = "1" #&CDS_SEC = "1";
"1":   PN = "1"  !CDS_PN = "1";
"2":   PN = "2"  !CDS_PN = "2";
BODY = "AT24MAC402_SOT23_5","I89": #LOCATION = "U7" !CDS_LOCATION = "U7" &SEC = "1" #&CDS_SEC = "1";
"GND":   PN = "2"  !CDS_PN = "2";
"SCL":   PN = "1"  !CDS_PN = "1";
"SDA":   PN = "3"  !CDS_PN = "3";
"VCC":   PN = "4"  !CDS_PN = "4";
"WP":   PN = "5"  !CDS_PN = "5";
BODY = "RESISTOR","I90": LOCATION = "R345" #&CDS_LOCATION = "R345" &SEC = "1" #&CDS_SEC = "1";
"1":   PN = "1"  !CDS_PN = "1";
"2":   PN = "2"  !CDS_PN = "2";
BODY = "CAPACITOR","I92": LOCATION = "C225" #&CDS_LOCATION = "C225" &SEC = "1" #&CDS_SEC = "1";
"1":   PN = "1"  !CDS_PN = "1";
"2":   PN = "2"  !CDS_PN = "2";
BODY = "RESISTOR","I94": LOCATION = "R1992" #&CDS_LOCATION = "R1992" &SEC = "1" #&CDS_SEC = "1";
"1":   PN = "1"  !CDS_PN = "1";
"2":   PN = "2"  !CDS_PN = "2";
BODY = "RESISTOR","I95": LOCATION = "R19" #&CDS_LOCATION = "R19" &SEC = "1" #&CDS_SEC = "1";
"1":   PN = "1"  !CDS_PN = "1";
"2":   PN = "2"  !CDS_PN = "2";
BODY = "RESISTOR","I96": LOCATION = "R1991" #&CDS_LOCATION = "R1991" &SEC = "1" #&CDS_SEC = "1";
"1":   PN = "1"  !CDS_PN = "1";
"2":   PN = "2"  !CDS_PN = "2";
BODY = "RESISTOR","I97": LOCATION = "R344" #&CDS_LOCATION = "R344" &SEC = "1" #&CDS_SEC = "1";
"1":   PN = "1"  !CDS_PN = "1";
"2":   PN = "2"  !CDS_PN = "2";
BODY = "RESISTOR","I100": LOCATION = "R175" #&CDS_LOCATION = "R175" &SEC = "1" #&CDS_SEC = "1";
"1":   PN = "1"  !CDS_PN = "1";
"2":   PN = "2"  !CDS_PN = "2";
BODY = "RESISTOR","I101": LOCATION = "R183" #&CDS_LOCATION = "R183" &SEC = "1" #&CDS_SEC = "1";
"1":   PN = "1"  !CDS_PN = "1";
"2":   PN = "2"  !CDS_PN = "2";
BODY = "RESISTOR","I102": LOCATION = "R176" #&CDS_LOCATION = "R176" &SEC = "1" #&CDS_SEC = "1";
"1":   PN = "1"  !CDS_PN = "1";
"2":   PN = "2"  !CDS_PN = "2";
BODY = "RESISTOR","I103": LOCATION = "R184" #&CDS_LOCATION = "R184" &SEC = "1" #&CDS_SEC = "1";
"1":   PN = "1"  !CDS_PN = "1";
"2":   PN = "2"  !CDS_PN = "2";
BODY = "RESISTOR","I111": LOCATION = "R313" #&CDS_LOCATION = "R313" &SEC = "1" #&CDS_SEC = "1";
"1":   PN = "1"  !CDS_PN = "1";
"2":   PN = "2"  !CDS_PN = "2";
BODY = "RESISTOR","I112": LOCATION = "R312" #&CDS_LOCATION = "R312" &SEC = "1" #&CDS_SEC = "1";
"1":   PN = "1"  !CDS_PN = "1";
"2":   PN = "2"  !CDS_PN = "2";
BODY = "RESISTOR","I115": LOCATION = "R311" #&CDS_LOCATION = "R311" &SEC = "1" #&CDS_SEC = "1";
"1":   PN = "1"  !CDS_PN = "1";
"2":   PN = "2"  !CDS_PN = "2";
BODY = "RESISTOR","I116": LOCATION = "R310" #&CDS_LOCATION = "R310" &SEC = "1" #&CDS_SEC = "1";
"1":   PN = "1"  !CDS_PN = "1";
"2":   PN = "2"  !CDS_PN = "2";
BODY = "RESISTOR","I125": LOCATION = "R60" #&CDS_LOCATION = "R60" &SEC = "1" #&CDS_SEC = "1";
"1":   PN = "1"  !CDS_PN = "1";
"2":   PN = "2"  !CDS_PN = "2";
BODY = "CONN_HDR_2X2_M_S_SMT","I126": #LOCATION = "J9" !CDS_LOCATION = "J9" &SEC = "1" #&CDS_SEC = "1";
"1":   PN = "1"  !CDS_PN = "1";
"2":   PN = "2"  !CDS_PN = "2";
"3":   PN = "3"  !CDS_PN = "3";
"4":   PN = "4"  !CDS_PN = "4";
BODY = "CONN_HDR_2X2_M_S_SMT","I127": #LOCATION = "J17" !CDS_LOCATION = "J17" &SEC = "1" #&CDS_SEC = "1";
"1":   PN = "1"  !CDS_PN = "1";
"2":   PN = "2"  !CDS_PN = "2";
"3":   PN = "3"  !CDS_PN = "3";
"4":   PN = "4"  !CDS_PN = "4";
BODY = "RESISTOR","I130": LOCATION = "R1" #&CDS_LOCATION = "R1" &SEC = "1" #&CDS_SEC = "1";
"1":   PN = "1"  !CDS_PN = "1";
"2":   PN = "2"  !CDS_PN = "2";
BODY = "24LC16BT_I_ST_TSSOP8","I148": LOCATION = "U19" #&CDS_LOCATION = "U19" &SEC = "2" #&CDS_SEC = "2";
"VCC":   PN = "8"  !CDS_PN = "8";
"VSS":   PN = "4"  !CDS_PN = "4";
BODY = "24LC16BT_I_ST_TSSOP8","I151": LOCATION = "U19" #&CDS_LOCATION = "U19" &SEC = "1" #&CDS_SEC = "1";
"A0":   PN = "1"  !CDS_PN = "1";
"A1":   PN = "2"  !CDS_PN = "2";
"A2":   PN = "3"  !CDS_PN = "3";
"SCL":   PN = "6"  !CDS_PN = "6";
"SDA":   PN = "5"  !CDS_PN = "5";
"WP":   PN = "7"  !CDS_PN = "7";
BODY = "RESISTOR","I153": LOCATION = "R158" #&CDS_LOCATION = "R158" &SEC = "1" #&CDS_SEC = "1";
"1":   PN = "1"  !CDS_PN = "1";
"2":   PN = "2"  !CDS_PN = "2";
BODY = "RESISTOR","I156": LOCATION = "R159" #&CDS_LOCATION = "R159" &SEC = "1" #&CDS_SEC = "1";
"1":   PN = "1"  !CDS_PN = "1";
"2":   PN = "2"  !CDS_PN = "2";
BODY = "RESISTOR","I160": LOCATION = "R160" #&CDS_LOCATION = "R160" &SEC = "1" #&CDS_SEC = "1";
"1":   PN = "1"  !CDS_PN = "1";
"2":   PN = "2"  !CDS_PN = "2";
BODY = "RESISTOR","I161": LOCATION = "R162" #&CDS_LOCATION = "R162" &SEC = "1" #&CDS_SEC = "1";
"1":   PN = "1"  !CDS_PN = "1";
"2":   PN = "2"  !CDS_PN = "2";
BODY = "RESISTOR","I162": LOCATION = "R45" #&CDS_LOCATION = "R45" &SEC = "1" #&CDS_SEC = "1";
"1":   PN = "1"  !CDS_PN = "1";
"2":   PN = "2"  !CDS_PN = "2";
BODY = "RESISTOR","I165": LOCATION = "R161" #&CDS_LOCATION = "R161" &SEC = "1" #&CDS_SEC = "1";
"1":   PN = "1"  !CDS_PN = "1";
"2":   PN = "2"  !CDS_PN = "2";
BODY = "RESISTOR","I166": LOCATION = "R163" #&CDS_LOCATION = "R163" &SEC = "1" #&CDS_SEC = "1";
"1":   PN = "1"  !CDS_PN = "1";
"2":   PN = "2"  !CDS_PN = "2";
BODY = "RESISTOR","I167": LOCATION = "R24" #&CDS_LOCATION = "R24" &SEC = "1" #&CDS_SEC = "1";
"1":   PN = "1"  !CDS_PN = "1";
"2":   PN = "2"  !CDS_PN = "2";
BODY = "RESISTOR","I169": LOCATION = "R3" #&CDS_LOCATION = "R3" &SEC = "1" #&CDS_SEC = "1";
"1":   PN = "1"  !CDS_PN = "1";
"2":   PN = "2"  !CDS_PN = "2";
BODY = "CAPACITOR","I171": LOCATION = "C1" #&CDS_LOCATION = "C1" &SEC = "1" #&CDS_SEC = "1";
"1":   PN = "1"  !CDS_PN = "1";
"2":   PN = "2"  !CDS_PN = "2";
BODY = "RESISTOR","I173": LOCATION = "R2" #&CDS_LOCATION = "R2" &SEC = "1" #&CDS_SEC = "1";
"1":   PN = "1"  !CDS_PN = "1";
"2":   PN = "2"  !CDS_PN = "2";
DRAWING = "@timecard_lib.timecard(sch_1):page6";
BODY = "RESISTOR","I14": LOCATION = "R20" #&CDS_LOCATION = "R20" &SEC = "1" #&CDS_SEC = "1";
"1":   PN = "1"  !CDS_PN = "1";
"2":   PN = "2"  !CDS_PN = "2";
BODY = "RESISTOR","I15": LOCATION = "R332" #&CDS_LOCATION = "R332" &SEC = "1" #&CDS_SEC = "1";
"1":   PN = "1"  !CDS_PN = "1";
"2":   PN = "2"  !CDS_PN = "2";
BODY = "RESISTOR","I16": LOCATION = "R21" #&CDS_LOCATION = "R21" &SEC = "1" #&CDS_SEC = "1";
"1":   PN = "1"  !CDS_PN = "1";
"2":   PN = "2"  !CDS_PN = "2";
BODY = "RESISTOR","I30": LOCATION = "R334" #&CDS_LOCATION = "R334" &SEC = "1" #&CDS_SEC = "1";
"1":   PN = "1"  !CDS_PN = "1";
"2":   PN = "2"  !CDS_PN = "2";
BODY = "RESISTOR","I31": LOCATION = "R333" #&CDS_LOCATION = "R333" &SEC = "1" #&CDS_SEC = "1";
"1":   PN = "1"  !CDS_PN = "1";
"2":   PN = "2"  !CDS_PN = "2";
BODY = "RESISTOR","I32": LOCATION = "R336" #&CDS_LOCATION = "R336" &SEC = "1" #&CDS_SEC = "1";
"1":   PN = "1"  !CDS_PN = "1";
"2":   PN = "2"  !CDS_PN = "2";
BODY = "RESISTOR","I33": LOCATION = "R338" #&CDS_LOCATION = "R338" &SEC = "1" #&CDS_SEC = "1";
"1":   PN = "1"  !CDS_PN = "1";
"2":   PN = "2"  !CDS_PN = "2";
BODY = "LM75BDP_TSSOP8","I34": LOCATION = "U8" #&CDS_LOCATION = "U8" &SEC = "1" #&CDS_SEC = "1";
"A0":   PN = "7"  !CDS_PN = "7";
"A1":   PN = "6"  !CDS_PN = "6";
"A2":   PN = "5"  !CDS_PN = "5";
"OS":   PN = "3"  !CDS_PN = "3";
"SCL":   PN = "2"  !CDS_PN = "2";
"SDA":   PN = "1"  !CDS_PN = "1";
BODY = "RESISTOR","I35": LOCATION = "R335" #&CDS_LOCATION = "R335" &SEC = "1" #&CDS_SEC = "1";
"1":   PN = "1"  !CDS_PN = "1";
"2":   PN = "2"  !CDS_PN = "2";
BODY = "RESISTOR","I36": LOCATION = "R337" #&CDS_LOCATION = "R337" &SEC = "1" #&CDS_SEC = "1";
"1":   PN = "1"  !CDS_PN = "1";
"2":   PN = "2"  !CDS_PN = "2";
BODY = "CAPACITOR","I37": LOCATION = "C39" #&CDS_LOCATION = "C39" &SEC = "1" #&CDS_SEC = "1";
"1":   PN = "1"  !CDS_PN = "1";
"2":   PN = "2"  !CDS_PN = "2";
BODY = "LM75BDP_TSSOP8","I38": LOCATION = "U8" #&CDS_LOCATION = "U8" &SEC = "2" #&CDS_SEC = "2";
"GND":   PN = "4"  !CDS_PN = "4";
"VCC":   PN = "8"  !CDS_PN = "8";
BODY = "RESISTOR","I41": LOCATION = "R340" #&CDS_LOCATION = "R340" &SEC = "1" #&CDS_SEC = "1";
"1":   PN = "1"  !CDS_PN = "1";
"2":   PN = "2"  !CDS_PN = "2";
BODY = "LM75BDP_TSSOP8","I59": LOCATION = "U35" #&CDS_LOCATION = "U35" &SEC = "1" #&CDS_SEC = "1";
"A0":   PN = "7"  !CDS_PN = "7";
"A1":   PN = "6"  !CDS_PN = "6";
"A2":   PN = "5"  !CDS_PN = "5";
"OS":   PN = "3"  !CDS_PN = "3";
"SCL":   PN = "2"  !CDS_PN = "2";
"SDA":   PN = "1"  !CDS_PN = "1";
BODY = "RESISTOR","I60": LOCATION = "R413" #&CDS_LOCATION = "R413" &SEC = "1" #&CDS_SEC = "1";
"1":   PN = "1"  !CDS_PN = "1";
"2":   PN = "2"  !CDS_PN = "2";
BODY = "RESISTOR","I64": LOCATION = "R422" #&CDS_LOCATION = "R422" &SEC = "1" #&CDS_SEC = "1";
"1":   PN = "1"  !CDS_PN = "1";
"2":   PN = "2"  !CDS_PN = "2";
BODY = "LM75BDP_TSSOP8","I66": LOCATION = "U36" #&CDS_LOCATION = "U36" &SEC = "2" #&CDS_SEC = "2";
"GND":   PN = "4"  !CDS_PN = "4";
"VCC":   PN = "8"  !CDS_PN = "8";
BODY = "CAPACITOR","I67": LOCATION = "C305" #&CDS_LOCATION = "C305" &SEC = "1" #&CDS_SEC = "1";
"1":   PN = "1"  !CDS_PN = "1";
"2":   PN = "2"  !CDS_PN = "2";
BODY = "RESISTOR","I69": LOCATION = "R418" #&CDS_LOCATION = "R418" &SEC = "1" #&CDS_SEC = "1";
"1":   PN = "1"  !CDS_PN = "1";
"2":   PN = "2"  !CDS_PN = "2";
BODY = "RESISTOR","I70": LOCATION = "R412" #&CDS_LOCATION = "R412" &SEC = "1" #&CDS_SEC = "1";
"1":   PN = "1"  !CDS_PN = "1";
"2":   PN = "2"  !CDS_PN = "2";
BODY = "RESISTOR","I71": LOCATION = "R408" #&CDS_LOCATION = "R408" &SEC = "1" #&CDS_SEC = "1";
"1":   PN = "1"  !CDS_PN = "1";
"2":   PN = "2"  !CDS_PN = "2";
BODY = "RESISTOR","I72": LOCATION = "R416" #&CDS_LOCATION = "R416" &SEC = "1" #&CDS_SEC = "1";
"1":   PN = "1"  !CDS_PN = "1";
"2":   PN = "2"  !CDS_PN = "2";
BODY = "RESISTOR","I73": LOCATION = "R409" #&CDS_LOCATION = "R409" &SEC = "1" #&CDS_SEC = "1";
"1":   PN = "1"  !CDS_PN = "1";
"2":   PN = "2"  !CDS_PN = "2";
BODY = "RESISTOR","I76": LOCATION = "R406" #&CDS_LOCATION = "R406" &SEC = "1" #&CDS_SEC = "1";
"1":   PN = "1"  !CDS_PN = "1";
"2":   PN = "2"  !CDS_PN = "2";
BODY = "LM75BDP_TSSOP8","I81": LOCATION = "U36" #&CDS_LOCATION = "U36" &SEC = "1" #&CDS_SEC = "1";
"A0":   PN = "7"  !CDS_PN = "7";
"A1":   PN = "6"  !CDS_PN = "6";
"A2":   PN = "5"  !CDS_PN = "5";
"OS":   PN = "3"  !CDS_PN = "3";
"SCL":   PN = "2"  !CDS_PN = "2";
"SDA":   PN = "1"  !CDS_PN = "1";
BODY = "RESISTOR","I84": LOCATION = "R419" #&CDS_LOCATION = "R419" &SEC = "1" #&CDS_SEC = "1";
"1":   PN = "1"  !CDS_PN = "1";
"2":   PN = "2"  !CDS_PN = "2";
BODY = "RESISTOR","I85": LOCATION = "R414" #&CDS_LOCATION = "R414" &SEC = "1" #&CDS_SEC = "1";
"1":   PN = "1"  !CDS_PN = "1";
"2":   PN = "2"  !CDS_PN = "2";
BODY = "RESISTOR","I86": LOCATION = "R410" #&CDS_LOCATION = "R410" &SEC = "1" #&CDS_SEC = "1";
"1":   PN = "1"  !CDS_PN = "1";
"2":   PN = "2"  !CDS_PN = "2";
BODY = "RESISTOR","I88": LOCATION = "R423" #&CDS_LOCATION = "R423" &SEC = "1" #&CDS_SEC = "1";
"1":   PN = "1"  !CDS_PN = "1";
"2":   PN = "2"  !CDS_PN = "2";
BODY = "LM75BDP_TSSOP8","I90": LOCATION = "U35" #&CDS_LOCATION = "U35" &SEC = "2" #&CDS_SEC = "2";
"GND":   PN = "4"  !CDS_PN = "4";
"VCC":   PN = "8"  !CDS_PN = "8";
BODY = "CAPACITOR","I91": LOCATION = "C306" #&CDS_LOCATION = "C306" &SEC = "1" #&CDS_SEC = "1";
"1":   PN = "1"  !CDS_PN = "1";
"2":   PN = "2"  !CDS_PN = "2";
BODY = "RESISTOR","I93": LOCATION = "R417" #&CDS_LOCATION = "R417" &SEC = "1" #&CDS_SEC = "1";
"1":   PN = "1"  !CDS_PN = "1";
"2":   PN = "2"  !CDS_PN = "2";
BODY = "RESISTOR","I94": LOCATION = "R415" #&CDS_LOCATION = "R415" &SEC = "1" #&CDS_SEC = "1";
"1":   PN = "1"  !CDS_PN = "1";
"2":   PN = "2"  !CDS_PN = "2";
BODY = "RESISTOR","I95": LOCATION = "R411" #&CDS_LOCATION = "R411" &SEC = "1" #&CDS_SEC = "1";
"1":   PN = "1"  !CDS_PN = "1";
"2":   PN = "2"  !CDS_PN = "2";
BODY = "RESISTOR","I100": LOCATION = "R407" #&CDS_LOCATION = "R407" &SEC = "1" #&CDS_SEC = "1";
"1":   PN = "1"  !CDS_PN = "1";
"2":   PN = "2"  !CDS_PN = "2";
DRAWING = "@timecard_lib.timecard(sch_1):page9";
BODY = "RESISTOR","I6": LOCATION = "R74" #&CDS_LOCATION = "R74" &SEC = "1" #&CDS_SEC = "1";
"1":   PN = "1"  !CDS_PN = "1";
"2":   PN = "2"  !CDS_PN = "2";
BODY = "RESISTOR","I7": LOCATION = "R75" #&CDS_LOCATION = "R75" &SEC = "1" #&CDS_SEC = "1";
"1":   PN = "1"  !CDS_PN = "1";
"2":   PN = "2"  !CDS_PN = "2";
BODY = "RESISTOR","I11": LOCATION = "R77" #&CDS_LOCATION = "R77" &SEC = "1" #&CDS_SEC = "1";
"1":   PN = "1"  !CDS_PN = "1";
"2":   PN = "2"  !CDS_PN = "2";
BODY = "RESISTOR","I12": LOCATION = "R76" #&CDS_LOCATION = "R76" &SEC = "1" #&CDS_SEC = "1";
"1":   PN = "1"  !CDS_PN = "1";
"2":   PN = "2"  !CDS_PN = "2";
BODY = "XTAL_2","I16": LOCATION = "Y1" #&CDS_LOCATION = "Y1" &SEC = "1" #&CDS_SEC = "1";
"1":   PN = "1"  !CDS_PN = "1";
"2":   PN = "2"  !CDS_PN = "2";
BODY = "CAPACITOR","I17": LOCATION = "C51" #&CDS_LOCATION = "C51" &SEC = "1" #&CDS_SEC = "1";
"1":   PN = "1"  !CDS_PN = "1";
"2":   PN = "2"  !CDS_PN = "2";
BODY = "FERRITEBEAD","I22": LOCATION = "L19" #&CDS_LOCATION = "L19" &SEC = "1" #&CDS_SEC = "1";
"1":   PN = "1"  !CDS_PN = "1";
"2":   PN = "2"  !CDS_PN = "2";
BODY = "CAPACITOR","I23": LOCATION = "C280" #&CDS_LOCATION = "C280" &SEC = "1" #&CDS_SEC = "1";
"1":   PN = "1"  !CDS_PN = "1";
"2":   PN = "2"  !CDS_PN = "2";
BODY = "CAPACITOR","I21": LOCATION = "C279" #&CDS_LOCATION = "C279" &SEC = "1" #&CDS_SEC = "1";
"1":   PN = "1"  !CDS_PN = "1";
"2":   PN = "2"  !CDS_PN = "2";
BODY = "CAPACITOR","I24": LOCATION = "C281" #&CDS_LOCATION = "C281" &SEC = "1" #&CDS_SEC = "1";
"1":   PN = "1"  !CDS_PN = "1";
"2":   PN = "2"  !CDS_PN = "2";
BODY = "BNO080_LGA_28","I29": LOCATION = "U29" #&CDS_LOCATION = "U29" &SEC = "1" #&CDS_SEC = "1";
"BOOTN":   PN = "4"  !CDS_PN = "4";
"CAP":   PN = "9"  !CDS_PN = "9";
"CLKSEL0":   PN = "10"  !CDS_PN = "10";
"ENV_SCL":   PN = "15"  !CDS_PN = "15";
"ENV_SDA":   PN = "16"  !CDS_PN = "16";
"GND_1":   PN = "2"  !CDS_PN = "2";
"GND_2":   PN = "25"  !CDS_PN = "25";
"H_CS*":   PN = "18"  !CDS_PN = "18";
"H_INTN":   PN = "14"  !CDS_PN = "14";
"H_SCL/SCK/RX":   PN = "19"  !CDS_PN = "19";
"H_SDA/H_MISO/TX":   PN = "20"  !CDS_PN = "20";
"PS0/WAKE":   PN = "6"  !CDS_PN = "6";
"PS1":   PN = "5"  !CDS_PN = "5";
"RESV_NC_1":   PN = "1"  !CDS_PN = "1";
"RESV_NC_2":   PN = "7"  !CDS_PN = "7";
"RESV_NC_3":   PN = "8"  !CDS_PN = "8";
"RESV_NC_4":   PN = "12"  !CDS_PN = "12";
"RESV_NC_5":   PN = "13"  !CDS_PN = "13";
"RESV_NC_6":   PN = "21"  !CDS_PN = "21";
"RESV_NC_7":   PN = "22"  !CDS_PN = "22";
"RESV_NC_8":   PN = "23"  !CDS_PN = "23";
"RESV_NC_9":   PN = "24"  !CDS_PN = "24";
"RST*":   PN = "11"  !CDS_PN = "11";
"SA0/H_MOSI":   PN = "17"  !CDS_PN = "17";
"VDD":   PN = "3"  !CDS_PN = "3";
"VDDIO":   PN = "28"  !CDS_PN = "28";
"XIN32":   PN = "27"  !CDS_PN = "27";
"XOUT32/CLKSEL1":   PN = "26"  !CDS_PN = "26";
BODY = "RESISTOR","I31": LOCATION = "R79" #&CDS_LOCATION = "R79" &SEC = "1" #&CDS_SEC = "1";
"1":   PN = "1"  !CDS_PN = "1";
"2":   PN = "2"  !CDS_PN = "2";
BODY = "RESISTOR","I32": LOCATION = "R80" #&CDS_LOCATION = "R80" &SEC = "1" #&CDS_SEC = "1";
"1":   PN = "1"  !CDS_PN = "1";
"2":   PN = "2"  !CDS_PN = "2";
BODY = "RESISTOR","I37": LOCATION = "R304" #&CDS_LOCATION = "R304" &SEC = "1" #&CDS_SEC = "1";
"1":   PN = "1"  !CDS_PN = "1";
"2":   PN = "2"  !CDS_PN = "2";
BODY = "RESISTOR","I38": #LOCATION = "R289" !CDS_LOCATION = "R289" &SEC = "1" #&CDS_SEC = "1";
"1":   PN = "1"  !CDS_PN = "1";
"2":   PN = "2"  !CDS_PN = "2";
BODY = "RESISTOR","I41": LOCATION = "R78" #&CDS_LOCATION = "R78" &SEC = "1" #&CDS_SEC = "1";
"1":   PN = "1"  !CDS_PN = "1";
"2":   PN = "2"  !CDS_PN = "2";
BODY = "RESISTOR","I43": LOCATION = "R301" #&CDS_LOCATION = "R301" &SEC = "1" #&CDS_SEC = "1";
"1":   PN = "1"  !CDS_PN = "1";
"2":   PN = "2"  !CDS_PN = "2";
BODY = "RESISTOR","I44": LOCATION = "R291" #&CDS_LOCATION = "R291" &SEC = "1" #&CDS_SEC = "1";
"1":   PN = "1"  !CDS_PN = "1";
"2":   PN = "2"  !CDS_PN = "2";
BODY = "RESISTOR","I47": LOCATION = "R307" #&CDS_LOCATION = "R307" &SEC = "1" #&CDS_SEC = "1";
"1":   PN = "1"  !CDS_PN = "1";
"2":   PN = "2"  !CDS_PN = "2";
BODY = "RESISTOR","I49": LOCATION = "R305" #&CDS_LOCATION = "R305" &SEC = "1" #&CDS_SEC = "1";
"1":   PN = "1"  !CDS_PN = "1";
"2":   PN = "2"  !CDS_PN = "2";
BODY = "RESISTOR","I50": LOCATION = "R303" #&CDS_LOCATION = "R303" &SEC = "1" #&CDS_SEC = "1";
"1":   PN = "1"  !CDS_PN = "1";
"2":   PN = "2"  !CDS_PN = "2";
BODY = "RESISTOR","I51": #LOCATION = "R290" !CDS_LOCATION = "R290" &SEC = "1" #&CDS_SEC = "1";
"1":   PN = "1"  !CDS_PN = "1";
"2":   PN = "2"  !CDS_PN = "2";
BODY = "RESISTOR","I52": LOCATION = "R302" #&CDS_LOCATION = "R302" &SEC = "1" #&CDS_SEC = "1";
"1":   PN = "1"  !CDS_PN = "1";
"2":   PN = "2"  !CDS_PN = "2";
BODY = "CAPACITOR","I53": LOCATION = "C285" #&CDS_LOCATION = "C285" &SEC = "1" #&CDS_SEC = "1";
"1":   PN = "1"  !CDS_PN = "1";
"2":   PN = "2"  !CDS_PN = "2";
BODY = "CAPACITOR","I54": #LOCATION = "C47" !CDS_LOCATION = "C47" &SEC = "1" #&CDS_SEC = "1";
"1":   PN = "1"  !CDS_PN = "1";
"2":   PN = "2"  !CDS_PN = "2";
BODY = "RESISTOR","I55": LOCATION = "R306" #&CDS_LOCATION = "R306" &SEC = "1" #&CDS_SEC = "1";
"1":   PN = "1"  !CDS_PN = "1";
"2":   PN = "2"  !CDS_PN = "2";
BODY = "TP_PIONT","I63": LOCATION = "TP61" #&CDS_LOCATION = "TP61" &SEC = "1" #&CDS_SEC = "1";
"1":   PN = "1"  !CDS_PN = "1";
BODY = "RESISTOR","I64": LOCATION = "R330" #&CDS_LOCATION = "R330" &SEC = "1" #&CDS_SEC = "1";
"1":   PN = "1"  !CDS_PN = "1";
"2":   PN = "2"  !CDS_PN = "2";
BODY = "RESISTOR","I65": LOCATION = "R341" #&CDS_LOCATION = "R341" &SEC = "1" #&CDS_SEC = "1";
"1":   PN = "1"  !CDS_PN = "1";
"2":   PN = "2"  !CDS_PN = "2";
BODY = "RESISTOR","I66": LOCATION = "R342" #&CDS_LOCATION = "R342" &SEC = "1" #&CDS_SEC = "1";
"1":   PN = "1"  !CDS_PN = "1";
"2":   PN = "2"  !CDS_PN = "2";
BODY = "RESISTOR","I67": LOCATION = "R363" #&CDS_LOCATION = "R363" &SEC = "1" #&CDS_SEC = "1";
"1":   PN = "1"  !CDS_PN = "1";
"2":   PN = "2"  !CDS_PN = "2";
BODY = "RESISTOR","I70": LOCATION = "R168" #&CDS_LOCATION = "R168" &SEC = "1" #&CDS_SEC = "1";
"1":   PN = "1"  !CDS_PN = "1";
"2":   PN = "2"  !CDS_PN = "2";
BODY = "TP_PIONT","I71": LOCATION = "TP1" #&CDS_LOCATION = "TP1" &SEC = "1" #&CDS_SEC = "1";
"1":   PN = "1"  !CDS_PN = "1";
BODY = "TP_PIONT","I72": LOCATION = "TP2" #&CDS_LOCATION = "TP2" &SEC = "1" #&CDS_SEC = "1";
"1":   PN = "1"  !CDS_PN = "1";
DRAWING = "@timecard_lib.timecard(sch_1):page14";
BODY = "OPTICAL","I11": LOCATION = "DS2" #&CDS_LOCATION = "DS2" &SEC = "1" #&CDS_SEC = "1";
"A":   PN = "A"  !CDS_PN = "A";
"C":   PN = "C"  !CDS_PN = "C";
BODY = "OPTICAL","I12": LOCATION = "DS1" #&CDS_LOCATION = "DS1" &SEC = "1" #&CDS_SEC = "1";
"A":   PN = "A"  !CDS_PN = "A";
"C":   PN = "C"  !CDS_PN = "C";
BODY = "RESISTOR","I44": LOCATION = "R180" #&CDS_LOCATION = "R180" &SEC = "1" #&CDS_SEC = "1";
"1":   PN = "1"  !CDS_PN = "1";
"2":   PN = "2"  !CDS_PN = "2";
BODY = "RESISTOR","I58": LOCATION = "R108" #&CDS_LOCATION = "R108" &SEC = "1" #&CDS_SEC = "1";
"1":   PN = "1"  !CDS_PN = "1";
"2":   PN = "2"  !CDS_PN = "2";
BODY = "RESISTOR","I60": LOCATION = "R139" #&CDS_LOCATION = "R139" &SEC = "1" #&CDS_SEC = "1";
"1":   PN = "1"  !CDS_PN = "1";
"2":   PN = "2"  !CDS_PN = "2";
BODY = "RESISTOR","I63": LOCATION = "R138" #&CDS_LOCATION = "R138" &SEC = "1" #&CDS_SEC = "1";
"1":   PN = "1"  !CDS_PN = "1";
"2":   PN = "2"  !CDS_PN = "2";
BODY = "RESISTOR","I65": LOCATION = "R256" #&CDS_LOCATION = "R256" &SEC = "1" #&CDS_SEC = "1";
"1":   PN = "1"  !CDS_PN = "1";
"2":   PN = "2"  !CDS_PN = "2";
BODY = "RESISTOR","I66": LOCATION = "R262" #&CDS_LOCATION = "R262" &SEC = "1" #&CDS_SEC = "1";
"1":   PN = "1"  !CDS_PN = "1";
"2":   PN = "2"  !CDS_PN = "2";
BODY = "RESISTOR","I67": LOCATION = "R257" #&CDS_LOCATION = "R257" &SEC = "1" #&CDS_SEC = "1";
"1":   PN = "1"  !CDS_PN = "1";
"2":   PN = "2"  !CDS_PN = "2";
BODY = "RESISTOR","I68": LOCATION = "R258" #&CDS_LOCATION = "R258" &SEC = "1" #&CDS_SEC = "1";
"1":   PN = "1"  !CDS_PN = "1";
"2":   PN = "2"  !CDS_PN = "2";
BODY = "RESISTOR","I69": LOCATION = "R259" #&CDS_LOCATION = "R259" &SEC = "1" #&CDS_SEC = "1";
"1":   PN = "1"  !CDS_PN = "1";
"2":   PN = "2"  !CDS_PN = "2";
BODY = "RESISTOR","I70": LOCATION = "R261" #&CDS_LOCATION = "R261" &SEC = "1" #&CDS_SEC = "1";
"1":   PN = "1"  !CDS_PN = "1";
"2":   PN = "2"  !CDS_PN = "2";
BODY = "RESISTOR","I72": LOCATION = "R279" #&CDS_LOCATION = "R279" &SEC = "1" #&CDS_SEC = "1";
"1":   PN = "1"  !CDS_PN = "1";
"2":   PN = "2"  !CDS_PN = "2";
BODY = "RESISTOR","I74": LOCATION = "R280" #&CDS_LOCATION = "R280" &SEC = "1" #&CDS_SEC = "1";
"1":   PN = "1"  !CDS_PN = "1";
"2":   PN = "2"  !CDS_PN = "2";
BODY = "RESISTOR","I107": LOCATION = "R385" #&CDS_LOCATION = "R385" &SEC = "1" #&CDS_SEC = "1";
"1":   PN = "1"  !CDS_PN = "1";
"2":   PN = "2"  !CDS_PN = "2";
BODY = "RESISTOR","I108": LOCATION = "R386" #&CDS_LOCATION = "R386" &SEC = "1" #&CDS_SEC = "1";
"1":   PN = "1"  !CDS_PN = "1";
"2":   PN = "2"  !CDS_PN = "2";
BODY = "RESISTOR","I110": LOCATION = "R387" #&CDS_LOCATION = "R387" &SEC = "1" #&CDS_SEC = "1";
"1":   PN = "1"  !CDS_PN = "1";
"2":   PN = "2"  !CDS_PN = "2";
BODY = "OPTICAL","I136": #LOCATION = "DS3" !CDS_LOCATION = "DS3" &SEC = "1" #&CDS_SEC = "1";
"A":   PN = "A"  !CDS_PN = "A";
"C":   PN = "C"  !CDS_PN = "C";
BODY = "OPTICAL","I137": #LOCATION = "DS4" !CDS_LOCATION = "DS4" &SEC = "1" #&CDS_SEC = "1";
"A":   PN = "A"  !CDS_PN = "A";
"C":   PN = "C"  !CDS_PN = "C";
BODY = "OPTICAL","I138": #LOCATION = "DS10" !CDS_LOCATION = "DS10" &SEC = "1" #&CDS_SEC = "1";
"A":   PN = "A"  !CDS_PN = "A";
"C":   PN = "C"  !CDS_PN = "C";
BODY = "OPTICAL","I139": #LOCATION = "DS11" !CDS_LOCATION = "DS11" &SEC = "1" #&CDS_SEC = "1";
"A":   PN = "A"  !CDS_PN = "A";
"C":   PN = "C"  !CDS_PN = "C";
BODY = "OPTICAL","I140": #LOCATION = "DS6" !CDS_LOCATION = "DS6" &SEC = "1" #&CDS_SEC = "1";
"A":   PN = "A"  !CDS_PN = "A";
"C":   PN = "C"  !CDS_PN = "C";
BODY = "OPTICAL","I141": #LOCATION = "DS7" !CDS_LOCATION = "DS7" &SEC = "1" #&CDS_SEC = "1";
"A":   PN = "A"  !CDS_PN = "A";
"C":   PN = "C"  !CDS_PN = "C";
BODY = "OPTICAL","I142": #LOCATION = "DS8" !CDS_LOCATION = "DS8" &SEC = "1" #&CDS_SEC = "1";
"A":   PN = "A"  !CDS_PN = "A";
"C":   PN = "C"  !CDS_PN = "C";
BODY = "OPTICAL","I143": #LOCATION = "DS5" !CDS_LOCATION = "DS5" &SEC = "1" #&CDS_SEC = "1";
"A":   PN = "A"  !CDS_PN = "A";
"C":   PN = "C"  !CDS_PN = "C";
BODY = "RESISTOR","I146": #LOCATION = "R390" !CDS_LOCATION = "R390" &SEC = "1" #&CDS_SEC = "1";
"1":   PN = "1"  !CDS_PN = "1";
"2":   PN = "2"  !CDS_PN = "2";
BODY = "RESISTOR","I147": #LOCATION = "R388" !CDS_LOCATION = "R388" &SEC = "1" #&CDS_SEC = "1";
"1":   PN = "1"  !CDS_PN = "1";
"2":   PN = "2"  !CDS_PN = "2";
BODY = "RESISTOR","I148": #LOCATION = "R389" !CDS_LOCATION = "R389" &SEC = "1" #&CDS_SEC = "1";
"1":   PN = "1"  !CDS_PN = "1";
"2":   PN = "2"  !CDS_PN = "2";
BODY = "RESISTOR","I149": #LOCATION = "R392" !CDS_LOCATION = "R392" &SEC = "1" #&CDS_SEC = "1";
"1":   PN = "1"  !CDS_PN = "1";
"2":   PN = "2"  !CDS_PN = "2";
BODY = "RESISTOR","I150": #LOCATION = "R391" !CDS_LOCATION = "R391" &SEC = "1" #&CDS_SEC = "1";
"1":   PN = "1"  !CDS_PN = "1";
"2":   PN = "2"  !CDS_PN = "2";
BODY = "RESISTOR","I151": #LOCATION = "R393" !CDS_LOCATION = "R393" &SEC = "1" #&CDS_SEC = "1";
"1":   PN = "1"  !CDS_PN = "1";
"2":   PN = "2"  !CDS_PN = "2";
BODY = "RESISTOR","I152": #LOCATION = "R395" !CDS_LOCATION = "R395" &SEC = "1" #&CDS_SEC = "1";
"1":   PN = "1"  !CDS_PN = "1";
"2":   PN = "2"  !CDS_PN = "2";
BODY = "RESISTOR","I153": #LOCATION = "R394" !CDS_LOCATION = "R394" &SEC = "1" #&CDS_SEC = "1";
"1":   PN = "1"  !CDS_PN = "1";
"2":   PN = "2"  !CDS_PN = "2";
BODY = "RESISTOR","I154": #LOCATION = "R396" !CDS_LOCATION = "R396" &SEC = "1" #&CDS_SEC = "1";
"1":   PN = "1"  !CDS_PN = "1";
"2":   PN = "2"  !CDS_PN = "2";
BODY = "RESISTOR","I155": #LOCATION = "R398" !CDS_LOCATION = "R398" &SEC = "1" #&CDS_SEC = "1";
"1":   PN = "1"  !CDS_PN = "1";
"2":   PN = "2"  !CDS_PN = "2";
BODY = "RESISTOR","I156": #LOCATION = "R397" !CDS_LOCATION = "R397" &SEC = "1" #&CDS_SEC = "1";
"1":   PN = "1"  !CDS_PN = "1";
"2":   PN = "2"  !CDS_PN = "2";
BODY = "RESISTOR","I157": #LOCATION = "R399" !CDS_LOCATION = "R399" &SEC = "1" #&CDS_SEC = "1";
"1":   PN = "1"  !CDS_PN = "1";
"2":   PN = "2"  !CDS_PN = "2";
BODY = "RESISTOR","I160": LOCATION = "R124" #&CDS_LOCATION = "R124" &SEC = "1" #&CDS_SEC = "1";
"1":   PN = "1"  !CDS_PN = "1";
"2":   PN = "2"  !CDS_PN = "2";
BODY = "RESISTOR","I161": LOCATION = "R125" #&CDS_LOCATION = "R125" &SEC = "1" #&CDS_SEC = "1";
"1":   PN = "1"  !CDS_PN = "1";
"2":   PN = "2"  !CDS_PN = "2";
BODY = "RESISTOR","I163": LOCATION = "R272" #&CDS_LOCATION = "R272" &SEC = "1" #&CDS_SEC = "1";
"1":   PN = "1"  !CDS_PN = "1";
"2":   PN = "2"  !CDS_PN = "2";
BODY = "RESISTOR","I165": LOCATION = "R273" #&CDS_LOCATION = "R273" &SEC = "1" #&CDS_SEC = "1";
"1":   PN = "1"  !CDS_PN = "1";
"2":   PN = "2"  !CDS_PN = "2";
BODY = "RESISTOR","I168": LOCATION = "R374" #&CDS_LOCATION = "R374" &SEC = "1" #&CDS_SEC = "1";
"1":   PN = "1"  !CDS_PN = "1";
"2":   PN = "2"  !CDS_PN = "2";
BODY = "RESISTOR","I170": LOCATION = "R425" #&CDS_LOCATION = "R425" &SEC = "1" #&CDS_SEC = "1";
"1":   PN = "1"  !CDS_PN = "1";
"2":   PN = "2"  !CDS_PN = "2";
BODY = "RESISTOR","I171": LOCATION = "R274" #&CDS_LOCATION = "R274" &SEC = "1" #&CDS_SEC = "1";
"1":   PN = "1"  !CDS_PN = "1";
"2":   PN = "2"  !CDS_PN = "2";
BODY = "RESISTOR","I174": LOCATION = "R375" #&CDS_LOCATION = "R375" &SEC = "1" #&CDS_SEC = "1";
"1":   PN = "1"  !CDS_PN = "1";
"2":   PN = "2"  !CDS_PN = "2";
BODY = "RESISTOR","I176": LOCATION = "R401" #&CDS_LOCATION = "R401" &SEC = "1" #&CDS_SEC = "1";
"1":   PN = "1"  !CDS_PN = "1";
"2":   PN = "2"  !CDS_PN = "2";
BODY = "RESISTOR","I177": LOCATION = "R400" #&CDS_LOCATION = "R400" &SEC = "1" #&CDS_SEC = "1";
"1":   PN = "1"  !CDS_PN = "1";
"2":   PN = "2"  !CDS_PN = "2";
BODY = "RESISTOR","I179": LOCATION = "R426" #&CDS_LOCATION = "R426" &SEC = "1" #&CDS_SEC = "1";
"1":   PN = "1"  !CDS_PN = "1";
"2":   PN = "2"  !CDS_PN = "2";
BODY = "RESISTOR","I181": LOCATION = "R373" #&CDS_LOCATION = "R373" &SEC = "1" #&CDS_SEC = "1";
"1":   PN = "1"  !CDS_PN = "1";
"2":   PN = "2"  !CDS_PN = "2";
BODY = "RESISTOR","I184": LOCATION = "R376" #&CDS_LOCATION = "R376" &SEC = "1" #&CDS_SEC = "1";
"1":   PN = "1"  !CDS_PN = "1";
"2":   PN = "2"  !CDS_PN = "2";
BODY = "RESISTOR","I186": LOCATION = "R424" #&CDS_LOCATION = "R424" &SEC = "1" #&CDS_SEC = "1";
"1":   PN = "1"  !CDS_PN = "1";
"2":   PN = "2"  !CDS_PN = "2";
BODY = "RESISTOR","I188": LOCATION = "R427" #&CDS_LOCATION = "R427" &SEC = "1" #&CDS_SEC = "1";
"1":   PN = "1"  !CDS_PN = "1";
"2":   PN = "2"  !CDS_PN = "2";
BODY = "RESISTOR","I190": LOCATION = "R118" #&CDS_LOCATION = "R118" &SEC = "1" #&CDS_SEC = "1";
"1":   PN = "1"  !CDS_PN = "1";
"2":   PN = "2"  !CDS_PN = "2";
BODY = "OPTICAL","I191": LOCATION = "DS19" #&CDS_LOCATION = "DS19" &SEC = "1" #&CDS_SEC = "1";
"A":   PN = "A"  !CDS_PN = "A";
"C":   PN = "C"  !CDS_PN = "C";
BODY = "RESISTOR","I192": LOCATION = "R119" #&CDS_LOCATION = "R119" &SEC = "1" #&CDS_SEC = "1";
"1":   PN = "1"  !CDS_PN = "1";
"2":   PN = "2"  !CDS_PN = "2";
BODY = "OPTICAL","I194": LOCATION = "DS20" #&CDS_LOCATION = "DS20" &SEC = "1" #&CDS_SEC = "1";
"A":   PN = "A"  !CDS_PN = "A";
"C":   PN = "C"  !CDS_PN = "C";
BODY = "IS32FL3207_QWLA3_TR_QFN29","I219": LOCATION = "U33" #&CDS_LOCATION = "U33" &SEC = "1" #&CDS_SEC = "1";
"AD":   PN = "2"  !CDS_PN = "2";
"GND_1":   PN = "4"  !CDS_PN = "4";
"GND_2":   PN = "11"  !CDS_PN = "11";
"GND_3":   PN = "18"  !CDS_PN = "18";
"GND_4":   PN = "25"  !CDS_PN = "25";
"ISET":   PN = "5"  !CDS_PN = "5";
"OUT1":   PN = "8"  !CDS_PN = "8";
"OUT2":   PN = "9"  !CDS_PN = "9";
"OUT3":   PN = "10"  !CDS_PN = "10";
"OUT4":   PN = "12"  !CDS_PN = "12";
"OUT5":   PN = "13"  !CDS_PN = "13";
"OUT6":   PN = "14"  !CDS_PN = "14";
"OUT7":   PN = "15"  !CDS_PN = "15";
"OUT8":   PN = "16"  !CDS_PN = "16";
"OUT9":   PN = "17"  !CDS_PN = "17";
"OUT10":   PN = "19"  !CDS_PN = "19";
"OUT11":   PN = "20"  !CDS_PN = "20";
"OUT12":   PN = "21"  !CDS_PN = "21";
"OUT13":   PN = "22"  !CDS_PN = "22";
"OUT14":   PN = "23"  !CDS_PN = "23";
"OUT15":   PN = "24"  !CDS_PN = "24";
"OUT16":   PN = "26"  !CDS_PN = "26";
"OUT17":   PN = "27"  !CDS_PN = "27";
"OUT18":   PN = "28"  !CDS_PN = "28";
"SCL":   PN = "7"  !CDS_PN = "7";
"SDA":   PN = "6"  !CDS_PN = "6";
"SDB*":   PN = "1"  !CDS_PN = "1";
"THRM_PAD":   PN = "29"  !CDS_PN = "29";
"VCC":   PN = "3"  !CDS_PN = "3";
BODY = "CAPACITOR","I237": LOCATION = "C315" #&CDS_LOCATION = "C315" &SEC = "1" #&CDS_SEC = "1";
"1":   PN = "1"  !CDS_PN = "1";
"2":   PN = "2"  !CDS_PN = "2";
BODY = "CAPACITOR","I238": LOCATION = "C314" #&CDS_LOCATION = "C314" &SEC = "1" #&CDS_SEC = "1";
"1":   PN = "1"  !CDS_PN = "1";
"2":   PN = "2"  !CDS_PN = "2";
BODY = "RESISTOR","I246": LOCATION = "R323" #&CDS_LOCATION = "R323" &SEC = "1" #&CDS_SEC = "1";
"1":   PN = "1"  !CDS_PN = "1";
"2":   PN = "2"  !CDS_PN = "2";
BODY = "RESISTOR","I247": LOCATION = "R324" #&CDS_LOCATION = "R324" &SEC = "1" #&CDS_SEC = "1";
"1":   PN = "1"  !CDS_PN = "1";
"2":   PN = "2"  !CDS_PN = "2";
BODY = "RESISTOR","I249": LOCATION = "R319" #&CDS_LOCATION = "R319" &SEC = "1" #&CDS_SEC = "1";
"1":   PN = "1"  !CDS_PN = "1";
"2":   PN = "2"  !CDS_PN = "2";
BODY = "CAPACITOR","I250": LOCATION = "C316" #&CDS_LOCATION = "C316" &SEC = "1" #&CDS_SEC = "1";
"1":   PN = "1"  !CDS_PN = "1";
"2":   PN = "2"  !CDS_PN = "2";
BODY = "RESISTOR","I257": LOCATION = "R322" #&CDS_LOCATION = "R322" &SEC = "1" #&CDS_SEC = "1";
"1":   PN = "1"  !CDS_PN = "1";
"2":   PN = "2"  !CDS_PN = "2";
BODY = "RESISTOR","I258": LOCATION = "R321" #&CDS_LOCATION = "R321" &SEC = "1" #&CDS_SEC = "1";
"1":   PN = "1"  !CDS_PN = "1";
"2":   PN = "2"  !CDS_PN = "2";
BODY = "RESISTOR","I259": LOCATION = "R317" #&CDS_LOCATION = "R317" &SEC = "1" #&CDS_SEC = "1";
"1":   PN = "1"  !CDS_PN = "1";
"2":   PN = "2"  !CDS_PN = "2";
BODY = "RESISTOR","I261": LOCATION = "R318" #&CDS_LOCATION = "R318" &SEC = "1" #&CDS_SEC = "1";
"1":   PN = "1"  !CDS_PN = "1";
"2":   PN = "2"  !CDS_PN = "2";
BODY = "RESISTOR","I264": #LOCATION = "R320" !CDS_LOCATION = "R320" &SEC = "1" #&CDS_SEC = "1";
"1":   PN = "1"  !CDS_PN = "1";
"2":   PN = "2"  !CDS_PN = "2";
BODY = "LED_4P_V14","I265": #LOCATION = "DS14" !CDS_LOCATION = "DS14" &SEC = "1" #&CDS_SEC = "1";
"1":   PN = "1"  !CDS_PN = "1";
"2":   PN = "2"  !CDS_PN = "2";
"3":   PN = "3"  !CDS_PN = "3";
"4":   PN = "4"  !CDS_PN = "4";
BODY = "LED_4P_V14","I266": #LOCATION = "DS15" !CDS_LOCATION = "DS15" &SEC = "1" #&CDS_SEC = "1";
"1":   PN = "1"  !CDS_PN = "1";
"2":   PN = "2"  !CDS_PN = "2";
"3":   PN = "3"  !CDS_PN = "3";
"4":   PN = "4"  !CDS_PN = "4";
BODY = "LED_4P_V14","I267": #LOCATION = "DS16" !CDS_LOCATION = "DS16" &SEC = "1" #&CDS_SEC = "1";
"1":   PN = "1"  !CDS_PN = "1";
"2":   PN = "2"  !CDS_PN = "2";
"3":   PN = "3"  !CDS_PN = "3";
"4":   PN = "4"  !CDS_PN = "4";
BODY = "LED_4P_V14","I268": #LOCATION = "DS17" !CDS_LOCATION = "DS17" &SEC = "1" #&CDS_SEC = "1";
"1":   PN = "1"  !CDS_PN = "1";
"2":   PN = "2"  !CDS_PN = "2";
"3":   PN = "3"  !CDS_PN = "3";
"4":   PN = "4"  !CDS_PN = "4";
BODY = "LED_4P_V14","I269": #LOCATION = "DS18" !CDS_LOCATION = "DS18" &SEC = "1" #&CDS_SEC = "1";
"1":   PN = "1"  !CDS_PN = "1";
"2":   PN = "2"  !CDS_PN = "2";
"3":   PN = "3"  !CDS_PN = "3";
"4":   PN = "4"  !CDS_PN = "4";
BODY = "RESISTOR","I288": LOCATION = "R169" #&CDS_LOCATION = "R169" &SEC = "1" #&CDS_SEC = "1";
"1":   PN = "1"  !CDS_PN = "1";
"2":   PN = "2"  !CDS_PN = "2";
BODY = "OPTICAL","I289": LOCATION = "DS12" #&CDS_LOCATION = "DS12" &SEC = "1" #&CDS_SEC = "1";
"A":   PN = "A"  !CDS_PN = "A";
"C":   PN = "C"  !CDS_PN = "C";
BODY = "OPTICAL","I292": #LOCATION = "DS9" !CDS_LOCATION = "DS9" &SEC = "1" #&CDS_SEC = "1";
"A":   PN = "A"  !CDS_PN = "A";
"C":   PN = "C"  !CDS_PN = "C";
BODY = "RESISTOR","I293": LOCATION = "R208" #&CDS_LOCATION = "R208" &SEC = "1" #&CDS_SEC = "1";
"1":   PN = "1"  !CDS_PN = "1";
"2":   PN = "2"  !CDS_PN = "2";
BODY = "RESISTOR","I298": LOCATION = "R364" #&CDS_LOCATION = "R364" &SEC = "1" #&CDS_SEC = "1";
"1":   PN = "1"  !CDS_PN = "1";
"2":   PN = "2"  !CDS_PN = "2";
BODY = "RESISTOR","I299": LOCATION = "R366" #&CDS_LOCATION = "R366" &SEC = "1" #&CDS_SEC = "1";
"1":   PN = "1"  !CDS_PN = "1";
"2":   PN = "2"  !CDS_PN = "2";
DRAWING = "@timecard_lib.timecard(sch_1):page517";
BODY = "CAPACITOR","I2": LOCATION = "C77" #&CDS_LOCATION = "C77" &SEC = "1" #&CDS_SEC = "1";
"1":   PN = "1"  !CDS_PN = "1";
"2":   PN = "2"  !CDS_PN = "2";
BODY = "RESISTOR","I3": LOCATION = "R51" #&CDS_LOCATION = "R51" &SEC = "1" #&CDS_SEC = "1";
"1":   PN = "1"  !CDS_PN = "1";
"2":   PN = "2"  !CDS_PN = "2";
BODY = "CAPACITOR","I6": LOCATION = "C76" #&CDS_LOCATION = "C76" &SEC = "1" #&CDS_SEC = "1";
"1":   PN = "1"  !CDS_PN = "1";
"2":   PN = "2"  !CDS_PN = "2";
BODY = "FERRITEBEAD","I7": LOCATION = "L8" #&CDS_LOCATION = "L8" &SEC = "1" #&CDS_SEC = "1";
"1":   PN = "1"  !CDS_PN = "1";
"2":   PN = "2"  !CDS_PN = "2";
BODY = "CAPACITOR","I9": LOCATION = "C49" #&CDS_LOCATION = "C49" &SEC = "1" #&CDS_SEC = "1";
"1":   PN = "1"  !CDS_PN = "1";
"2":   PN = "2"  !CDS_PN = "2";
BODY = "RESISTOR","I10": LOCATION = "R35" #&CDS_LOCATION = "R35" &SEC = "1" #&CDS_SEC = "1";
"1":   PN = "1"  !CDS_PN = "1";
"2":   PN = "2"  !CDS_PN = "2";
BODY = "RESISTOR","I11": LOCATION = "R52" #&CDS_LOCATION = "R52" &SEC = "1" #&CDS_SEC = "1";
"1":   PN = "1"  !CDS_PN = "1";
"2":   PN = "2"  !CDS_PN = "2";
BODY = "CAPACITOR","I12": LOCATION = "C46" #&CDS_LOCATION = "C46" &SEC = "1" #&CDS_SEC = "1";
"1":   PN = "1"  !CDS_PN = "1";
"2":   PN = "2"  !CDS_PN = "2";
BODY = "RESISTOR","I13": LOCATION = "R53" #&CDS_LOCATION = "R53" &SEC = "1" #&CDS_SEC = "1";
"1":   PN = "1"  !CDS_PN = "1";
"2":   PN = "2"  !CDS_PN = "2";
BODY = "CAPACITOR","I14": LOCATION = "C48" #&CDS_LOCATION = "C48" &SEC = "1" #&CDS_SEC = "1";
"1":   PN = "1"  !CDS_PN = "1";
"2":   PN = "2"  !CDS_PN = "2";
BODY = "CAPACITOR","I15": LOCATION = "C50" #&CDS_LOCATION = "C50" &SEC = "1" #&CDS_SEC = "1";
"1":   PN = "1"  !CDS_PN = "1";
"2":   PN = "2"  !CDS_PN = "2";
BODY = "CAPACITOR","I16": LOCATION = "C52" #&CDS_LOCATION = "C52" &SEC = "1" #&CDS_SEC = "1";
"1":   PN = "1"  !CDS_PN = "1";
"2":   PN = "2"  !CDS_PN = "2";
BODY = "CAPACITOR","I17": LOCATION = "C54" #&CDS_LOCATION = "C54" &SEC = "1" #&CDS_SEC = "1";
"1":   PN = "1"  !CDS_PN = "1";
"2":   PN = "2"  !CDS_PN = "2";
BODY = "RESISTOR","I18": LOCATION = "R36" #&CDS_LOCATION = "R36" &SEC = "1" #&CDS_SEC = "1";
"1":   PN = "1"  !CDS_PN = "1";
"2":   PN = "2"  !CDS_PN = "2";
BODY = "CAPACITOR","I19": LOCATION = "C55" #&CDS_LOCATION = "C55" &SEC = "1" #&CDS_SEC = "1";
"1":   PN = "1"  !CDS_PN = "1";
"2":   PN = "2"  !CDS_PN = "2";
BODY = "CAPACITOR","I21": LOCATION = "C53" #&CDS_LOCATION = "C53" &SEC = "1" #&CDS_SEC = "1";
"1":   PN = "1"  !CDS_PN = "1";
"2":   PN = "2"  !CDS_PN = "2";
BODY = "SOLDER_PREFORM","I24": LOCATION = "SP2" #&CDS_LOCATION = "SP2" &SEC = "1" #&CDS_SEC = "1";
"1":   PN = "1"  !CDS_PN = "1";
"2":   PN = "2"  !CDS_PN = "2";
BODY = "RESISTOR","I25": LOCATION = "R37" #&CDS_LOCATION = "R37" &SEC = "1" #&CDS_SEC = "1";
"1":   PN = "1"  !CDS_PN = "1";
"2":   PN = "2"  !CDS_PN = "2";
BODY = "RESISTOR","I26": LOCATION = "R38" #&CDS_LOCATION = "R38" &SEC = "1" #&CDS_SEC = "1";
"1":   PN = "1"  !CDS_PN = "1";
"2":   PN = "2"  !CDS_PN = "2";
BODY = "CAPACITOR","I27": LOCATION = "C56" #&CDS_LOCATION = "C56" &SEC = "1" #&CDS_SEC = "1";
"1":   PN = "1"  !CDS_PN = "1";
"2":   PN = "2"  !CDS_PN = "2";
BODY = "INDUCTOR_2","I28": LOCATION = "L2" #&CDS_LOCATION = "L2" &SEC = "1" #&CDS_SEC = "1";
"1":   PN = "1"  !CDS_PN = "1";
"2":   PN = "2"  !CDS_PN = "2";
BODY = "CAPACITOR","I29": LOCATION = "C57" #&CDS_LOCATION = "C57" &SEC = "1" #&CDS_SEC = "1";
"1":   PN = "1"  !CDS_PN = "1";
"2":   PN = "2"  !CDS_PN = "2";
BODY = "CAPACITOR","I30": LOCATION = "C16" #&CDS_LOCATION = "C16" &SEC = "1" #&CDS_SEC = "1";
"1":   PN = "1"  !CDS_PN = "1";
"2":   PN = "2"  !CDS_PN = "2";
BODY = "RESISTOR","I31": LOCATION = "R40" #&CDS_LOCATION = "R40" &SEC = "1" #&CDS_SEC = "1";
"1":   PN = "1"  !CDS_PN = "1";
"2":   PN = "2"  !CDS_PN = "2";
BODY = "RESISTOR","I32": LOCATION = "R39" #&CDS_LOCATION = "R39" &SEC = "1" #&CDS_SEC = "1";
"1":   PN = "1"  !CDS_PN = "1";
"2":   PN = "2"  !CDS_PN = "2";
BODY = "RESISTOR","I33": LOCATION = "R17" #&CDS_LOCATION = "R17" &SEC = "1" #&CDS_SEC = "1";
"1":   PN = "1"  !CDS_PN = "1";
"2":   PN = "2"  !CDS_PN = "2";
BODY = "CAPACITOR","I36": LOCATION = "C18" #&CDS_LOCATION = "C18" &SEC = "1" #&CDS_SEC = "1";
"1":   PN = "1"  !CDS_PN = "1";
"2":   PN = "2"  !CDS_PN = "2";
BODY = "CAPACITOR","I37": LOCATION = "C20" #&CDS_LOCATION = "C20" &SEC = "1" #&CDS_SEC = "1";
"1":   PN = "1"  !CDS_PN = "1";
"2":   PN = "2"  !CDS_PN = "2";
BODY = "CAPACITOR","I38": LOCATION = "C21" #&CDS_LOCATION = "C21" &SEC = "1" #&CDS_SEC = "1";
"1":   PN = "1"  !CDS_PN = "1";
"2":   PN = "2"  !CDS_PN = "2";
BODY = "CAPACITOR","I40": LOCATION = "C22" #&CDS_LOCATION = "C22" &SEC = "1" #&CDS_SEC = "1";
"1":   PN = "1"  !CDS_PN = "1";
"2":   PN = "2"  !CDS_PN = "2";
BODY = "RESISTOR","I41": LOCATION = "R54" #&CDS_LOCATION = "R54" &SEC = "1" #&CDS_SEC = "1";
"1":   PN = "1"  !CDS_PN = "1";
"2":   PN = "2"  !CDS_PN = "2";
BODY = "TPS54824RNVR_VQFN18","I42": LOCATION = "U6" #&CDS_LOCATION = "U6" &SEC = "1" #&CDS_SEC = "1";
"AGND":   PN = "12"  !CDS_PN = "12";
"BOOT":   PN = "1"  !CDS_PN = "1";
"COMP":   PN = "15"  !CDS_PN = "15";
"EN":   PN = "17"  !CDS_PN = "17";
"FB":   PN = "14"  !CDS_PN = "14";
"PGND_1":   PN = "3"  !CDS_PN = "3";
"PGND_2":   PN = "4"  !CDS_PN = "4";
"PGND_3":   PN = "5"  !CDS_PN = "5";
"PGND_4":   PN = "8"  !CDS_PN = "8";
"PGND_5":   PN = "9"  !CDS_PN = "9";
"PGND_6":   PN = "10"  !CDS_PN = "10";
"PGOOD":   PN = "18"  !CDS_PN = "18";
"RT/CLK":   PN = "13"  !CDS_PN = "13";
"SS/TRK":   PN = "16"  !CDS_PN = "16";
"SW_1":   PN = "6"  !CDS_PN = "6";
"SW_2":   PN = "7"  !CDS_PN = "7";
"VIN_1":   PN = "2"  !CDS_PN = "2";
"VIN_2":   PN = "11"  !CDS_PN = "11";
BODY = "RESISTOR","I47": LOCATION = "R263" #&CDS_LOCATION = "R263" &SEC = "1" #&CDS_SEC = "1";
"1":   PN = "1"  !CDS_PN = "1";
"2":   PN = "2"  !CDS_PN = "2";
BODY = "CAPACITOR","I51": LOCATION = "C286" #&CDS_LOCATION = "C286" &SEC = "1" #&CDS_SEC = "1";
"1":   PN = "1"  !CDS_PN = "1";
"2":   PN = "2"  !CDS_PN = "2";
DRAWING = "@timecard_lib.timecard(sch_1):page516";
BODY = "RESISTOR","I1": LOCATION = "R47" #&CDS_LOCATION = "R47" &SEC = "1" #&CDS_SEC = "1";
"1":   PN = "1"  !CDS_PN = "1";
"2":   PN = "2"  !CDS_PN = "2";
BODY = "CAPACITOR","I4": LOCATION = "C74" #&CDS_LOCATION = "C74" &SEC = "1" #&CDS_SEC = "1";
"1":   PN = "1"  !CDS_PN = "1";
"2":   PN = "2"  !CDS_PN = "2";
BODY = "CAPACITOR","I7": LOCATION = "C75" #&CDS_LOCATION = "C75" &SEC = "1" #&CDS_SEC = "1";
"1":   PN = "1"  !CDS_PN = "1";
"2":   PN = "2"  !CDS_PN = "2";
BODY = "RESISTOR","I9": LOCATION = "R48" #&CDS_LOCATION = "R48" &SEC = "1" #&CDS_SEC = "1";
"1":   PN = "1"  !CDS_PN = "1";
"2":   PN = "2"  !CDS_PN = "2";
BODY = "CAPACITOR","I10": LOCATION = "C29" #&CDS_LOCATION = "C29" &SEC = "1" #&CDS_SEC = "1";
"1":   PN = "1"  !CDS_PN = "1";
"2":   PN = "2"  !CDS_PN = "2";
BODY = "CAPACITOR","I11": LOCATION = "C31" #&CDS_LOCATION = "C31" &SEC = "1" #&CDS_SEC = "1";
"1":   PN = "1"  !CDS_PN = "1";
"2":   PN = "2"  !CDS_PN = "2";
BODY = "RESISTOR","I12": LOCATION = "R29" #&CDS_LOCATION = "R29" &SEC = "1" #&CDS_SEC = "1";
"1":   PN = "1"  !CDS_PN = "1";
"2":   PN = "2"  !CDS_PN = "2";
BODY = "CAPACITOR","I13": LOCATION = "C42" #&CDS_LOCATION = "C42" &SEC = "1" #&CDS_SEC = "1";
"1":   PN = "1"  !CDS_PN = "1";
"2":   PN = "2"  !CDS_PN = "2";
BODY = "RESISTOR","I14": LOCATION = "R30" #&CDS_LOCATION = "R30" &SEC = "1" #&CDS_SEC = "1";
"1":   PN = "1"  !CDS_PN = "1";
"2":   PN = "2"  !CDS_PN = "2";
BODY = "CAPACITOR","I15": LOCATION = "C43" #&CDS_LOCATION = "C43" &SEC = "1" #&CDS_SEC = "1";
"1":   PN = "1"  !CDS_PN = "1";
"2":   PN = "2"  !CDS_PN = "2";
BODY = "RESISTOR","I16": LOCATION = "R49" #&CDS_LOCATION = "R49" &SEC = "1" #&CDS_SEC = "1";
"1":   PN = "1"  !CDS_PN = "1";
"2":   PN = "2"  !CDS_PN = "2";
BODY = "FERRITEBEAD","I17": LOCATION = "L7" #&CDS_LOCATION = "L7" &SEC = "1" #&CDS_SEC = "1";
"1":   PN = "1"  !CDS_PN = "1";
"2":   PN = "2"  !CDS_PN = "2";
BODY = "CAPACITOR","I18": LOCATION = "C30" #&CDS_LOCATION = "C30" &SEC = "1" #&CDS_SEC = "1";
"1":   PN = "1"  !CDS_PN = "1";
"2":   PN = "2"  !CDS_PN = "2";
BODY = "CAPACITOR","I19": LOCATION = "C32" #&CDS_LOCATION = "C32" &SEC = "1" #&CDS_SEC = "1";
"1":   PN = "1"  !CDS_PN = "1";
"2":   PN = "2"  !CDS_PN = "2";
BODY = "CAPACITOR","I20": LOCATION = "C33" #&CDS_LOCATION = "C33" &SEC = "1" #&CDS_SEC = "1";
"1":   PN = "1"  !CDS_PN = "1";
"2":   PN = "2"  !CDS_PN = "2";
BODY = "CAPACITOR","I22": LOCATION = "C41" #&CDS_LOCATION = "C41" &SEC = "1" #&CDS_SEC = "1";
"1":   PN = "1"  !CDS_PN = "1";
"2":   PN = "2"  !CDS_PN = "2";
BODY = "SOLDER_PREFORM","I24": LOCATION = "SP1" #&CDS_LOCATION = "SP1" &SEC = "1" #&CDS_SEC = "1";
"1":   PN = "1"  !CDS_PN = "1";
"2":   PN = "2"  !CDS_PN = "2";
BODY = "RESISTOR","I25": LOCATION = "R32" #&CDS_LOCATION = "R32" &SEC = "1" #&CDS_SEC = "1";
"1":   PN = "1"  !CDS_PN = "1";
"2":   PN = "2"  !CDS_PN = "2";
BODY = "RESISTOR","I26": LOCATION = "R31" #&CDS_LOCATION = "R31" &SEC = "1" #&CDS_SEC = "1";
"1":   PN = "1"  !CDS_PN = "1";
"2":   PN = "2"  !CDS_PN = "2";
BODY = "CAPACITOR","I27": LOCATION = "C44" #&CDS_LOCATION = "C44" &SEC = "1" #&CDS_SEC = "1";
"1":   PN = "1"  !CDS_PN = "1";
"2":   PN = "2"  !CDS_PN = "2";
BODY = "RESISTOR","I28": LOCATION = "R50" #&CDS_LOCATION = "R50" &SEC = "1" #&CDS_SEC = "1";
"1":   PN = "1"  !CDS_PN = "1";
"2":   PN = "2"  !CDS_PN = "2";
BODY = "CAPACITOR","I29": LOCATION = "C11" #&CDS_LOCATION = "C11" &SEC = "1" #&CDS_SEC = "1";
"1":   PN = "1"  !CDS_PN = "1";
"2":   PN = "2"  !CDS_PN = "2";
BODY = "RESISTOR","I30": LOCATION = "R34" #&CDS_LOCATION = "R34" &SEC = "1" #&CDS_SEC = "1";
"1":   PN = "1"  !CDS_PN = "1";
"2":   PN = "2"  !CDS_PN = "2";
BODY = "RESISTOR","I31": LOCATION = "R6" #&CDS_LOCATION = "R6" &SEC = "1" #&CDS_SEC = "1";
"1":   PN = "1"  !CDS_PN = "1";
"2":   PN = "2"  !CDS_PN = "2";
BODY = "CAPACITOR","I32": LOCATION = "C12" #&CDS_LOCATION = "C12" &SEC = "1" #&CDS_SEC = "1";
"1":   PN = "1"  !CDS_PN = "1";
"2":   PN = "2"  !CDS_PN = "2";
BODY = "CAPACITOR","I33": LOCATION = "C13" #&CDS_LOCATION = "C13" &SEC = "1" #&CDS_SEC = "1";
"1":   PN = "1"  !CDS_PN = "1";
"2":   PN = "2"  !CDS_PN = "2";
BODY = "CAPACITOR","I35": LOCATION = "C14" #&CDS_LOCATION = "C14" &SEC = "1" #&CDS_SEC = "1";
"1":   PN = "1"  !CDS_PN = "1";
"2":   PN = "2"  !CDS_PN = "2";
BODY = "INDUCTOR_2","I36": LOCATION = "L1" #&CDS_LOCATION = "L1" &SEC = "1" #&CDS_SEC = "1";
"1":   PN = "1"  !CDS_PN = "1";
"2":   PN = "2"  !CDS_PN = "2";
BODY = "CAPACITOR","I37": LOCATION = "C45" #&CDS_LOCATION = "C45" &SEC = "1" #&CDS_SEC = "1";
"1":   PN = "1"  !CDS_PN = "1";
"2":   PN = "2"  !CDS_PN = "2";
BODY = "RESISTOR","I38": LOCATION = "R33" #&CDS_LOCATION = "R33" &SEC = "1" #&CDS_SEC = "1";
"1":   PN = "1"  !CDS_PN = "1";
"2":   PN = "2"  !CDS_PN = "2";
BODY = "CAPACITOR","I40": LOCATION = "C15" #&CDS_LOCATION = "C15" &SEC = "1" #&CDS_SEC = "1";
"1":   PN = "1"  !CDS_PN = "1";
"2":   PN = "2"  !CDS_PN = "2";
BODY = "TPS54824RNVR_VQFN18","I42": LOCATION = "U5" #&CDS_LOCATION = "U5" &SEC = "1" #&CDS_SEC = "1";
"AGND":   PN = "12"  !CDS_PN = "12";
"BOOT":   PN = "1"  !CDS_PN = "1";
"COMP":   PN = "15"  !CDS_PN = "15";
"EN":   PN = "17"  !CDS_PN = "17";
"FB":   PN = "14"  !CDS_PN = "14";
"PGND_1":   PN = "3"  !CDS_PN = "3";
"PGND_2":   PN = "4"  !CDS_PN = "4";
"PGND_3":   PN = "5"  !CDS_PN = "5";
"PGND_4":   PN = "8"  !CDS_PN = "8";
"PGND_5":   PN = "9"  !CDS_PN = "9";
"PGND_6":   PN = "10"  !CDS_PN = "10";
"PGOOD":   PN = "18"  !CDS_PN = "18";
"RT/CLK":   PN = "13"  !CDS_PN = "13";
"SS/TRK":   PN = "16"  !CDS_PN = "16";
"SW_1":   PN = "6"  !CDS_PN = "6";
"SW_2":   PN = "7"  !CDS_PN = "7";
"VIN_1":   PN = "2"  !CDS_PN = "2";
"VIN_2":   PN = "11"  !CDS_PN = "11";
BODY = "RESISTOR","I44": LOCATION = "R142" #&CDS_LOCATION = "R142" &SEC = "1" #&CDS_SEC = "1";
"1":   PN = "1"  !CDS_PN = "1";
"2":   PN = "2"  !CDS_PN = "2";
BODY = "RESISTOR","I45": LOCATION = "R294" #&CDS_LOCATION = "R294" &SEC = "1" #&CDS_SEC = "1";
"1":   PN = "1"  !CDS_PN = "1";
"2":   PN = "2"  !CDS_PN = "2";
DRAWING = "@timecard_lib.timecard(sch_1):page15";
BODY = "CAPACITOR","I156": LOCATION = "C3" #&CDS_LOCATION = "C3" &SEC = "1" #&CDS_SEC = "1";
"1":   PN = "1"  !CDS_PN = "1";
"2":   PN = "2"  !CDS_PN = "2";
BODY = "DIODE_2E","I159": LOCATION = "CR10" #&CDS_LOCATION = "CR10" &SEC = "1" #&CDS_SEC = "1";
"A":   PN = "A"  !CDS_PN = "A";
"C":   PN = "C"  !CDS_PN = "C";
BODY = "CAPACITOR","I160": LOCATION = "C2" #&CDS_LOCATION = "C2" &SEC = "1" #&CDS_SEC = "1";
"1":   PN = "1"  !CDS_PN = "1";
"2":   PN = "2"  !CDS_PN = "2";
BODY = "RESISTOR","I169": LOCATION = "R5" #&CDS_LOCATION = "R5" &SEC = "1" #&CDS_SEC = "1";
"1":   PN = "1"  !CDS_PN = "1";
"2":   PN = "2"  !CDS_PN = "2";
BODY = "RESISTOR","I170": LOCATION = "R4" #&CDS_LOCATION = "R4" &SEC = "1" #&CDS_SEC = "1";
"1":   PN = "1"  !CDS_PN = "1";
"2":   PN = "2"  !CDS_PN = "2";
BODY = "RESISTOR","I171": LOCATION = "R46" #&CDS_LOCATION = "R46" &SEC = "1" #&CDS_SEC = "1";
"1":   PN = "1"  !CDS_PN = "1";
"2":   PN = "2"  !CDS_PN = "2";
BODY = "CAPACITOR","I172": LOCATION = "C4" #&CDS_LOCATION = "C4" &SEC = "1" #&CDS_SEC = "1";
"1":   PN = "1"  !CDS_PN = "1";
"2":   PN = "2"  !CDS_PN = "2";
BODY = "RESISTOR","I173": LOCATION = "R8" #&CDS_LOCATION = "R8" &SEC = "1" #&CDS_SEC = "1";
"1":   PN = "1"  !CDS_PN = "1";
"2":   PN = "2"  !CDS_PN = "2";
BODY = "RESISTOR","I174": LOCATION = "R7" #&CDS_LOCATION = "R7" &SEC = "1" #&CDS_SEC = "1";
"1":   PN = "1"  !CDS_PN = "1";
"2":   PN = "2"  !CDS_PN = "2";
BODY = "RESISTOR","I183": LOCATION = "R10" #&CDS_LOCATION = "R10" &SEC = "1" #&CDS_SEC = "1";
"1":   PN = "1"  !CDS_PN = "1";
"2":   PN = "2"  !CDS_PN = "2";
BODY = "CAPACITOR","I185": LOCATION = "C7" #&CDS_LOCATION = "C7" &SEC = "1" #&CDS_SEC = "1";
"1":   PN = "1"  !CDS_PN = "1";
"2":   PN = "2"  !CDS_PN = "2";
BODY = "RESISTOR","I186": LOCATION = "R14" #&CDS_LOCATION = "R14" &SEC = "1" #&CDS_SEC = "1";
"1":   PN = "1"  !CDS_PN = "1";
"2":   PN = "2"  !CDS_PN = "2";
BODY = "RESISTOR","I188": LOCATION = "R16" #&CDS_LOCATION = "R16" &SEC = "1" #&CDS_SEC = "1";
"1":   PN = "1"  !CDS_PN = "1";
"2":   PN = "2"  !CDS_PN = "2";
BODY = "CAPACITOR","I196": LOCATION = "C6" #&CDS_LOCATION = "C6" &SEC = "1" #&CDS_SEC = "1";
"1":   PN = "1"  !CDS_PN = "1";
"2":   PN = "2"  !CDS_PN = "2";
BODY = "RESISTOR","I197": LOCATION = "R12" #&CDS_LOCATION = "R12" &SEC = "1" #&CDS_SEC = "1";
"1":   PN = "1"  !CDS_PN = "1";
"2":   PN = "2"  !CDS_PN = "2";
BODY = "RESISTOR","I198": LOCATION = "R9" #&CDS_LOCATION = "R9" &SEC = "1" #&CDS_SEC = "1";
"1":   PN = "1"  !CDS_PN = "1";
"2":   PN = "2"  !CDS_PN = "2";
BODY = "RESISTOR","I199": LOCATION = "R11" #&CDS_LOCATION = "R11" &SEC = "1" #&CDS_SEC = "1";
"1":   PN = "1"  !CDS_PN = "1";
"2":   PN = "2"  !CDS_PN = "2";
BODY = "CAPACITOR","I201": LOCATION = "C8" #&CDS_LOCATION = "C8" &SEC = "1" #&CDS_SEC = "1";
"1":   PN = "1"  !CDS_PN = "1";
"2":   PN = "2"  !CDS_PN = "2";
BODY = "RESISTOR","I202": LOCATION = "R13" #&CDS_LOCATION = "R13" &SEC = "1" #&CDS_SEC = "1";
"1":   PN = "1"  !CDS_PN = "1";
"2":   PN = "2"  !CDS_PN = "2";
BODY = "RESISTOR","I203": LOCATION = "R15" #&CDS_LOCATION = "R15" &SEC = "1" #&CDS_SEC = "1";
"1":   PN = "1"  !CDS_PN = "1";
"2":   PN = "2"  !CDS_PN = "2";
BODY = "DIODE_2","I204": LOCATION = "CR3" #&CDS_LOCATION = "CR3" &SEC = "1" #&CDS_SEC = "1";
"A":   PN = "A"  !CDS_PN = "A";
"C":   PN = "C"  !CDS_PN = "C";
BODY = "CAPACITOR","I206": LOCATION = "C9" #&CDS_LOCATION = "C9" &SEC = "1" #&CDS_SEC = "1";
"1":   PN = "1"  !CDS_PN = "1";
"2":   PN = "2"  !CDS_PN = "2";
BODY = "CAPACITOR","I207": LOCATION = "C10" #&CDS_LOCATION = "C10" &SEC = "1" #&CDS_SEC = "1";
"1":   PN = "1"  !CDS_PN = "1";
"2":   PN = "2"  !CDS_PN = "2";
BODY = "CAPACITOR","I211": LOCATION = "C5" #&CDS_LOCATION = "C5" &SEC = "1" #&CDS_SEC = "1";
"1":   PN = "1"  !CDS_PN = "1";
"2":   PN = "2"  !CDS_PN = "2";
BODY = "MP5022CGQV_Z_QFN22","I212": LOCATION = "U1" #&CDS_LOCATION = "U1" &SEC = "1" #&CDS_SEC = "1";
"AVIN":   PN = "12"  !CDS_PN = "12";
"EN":   PN = "1"  !CDS_PN = "1";
"ENTM":   PN = "3"  !CDS_PN = "3";
"FLTB":   PN = "9"  !CDS_PN = "9";
"GND":   PN = "7"  !CDS_PN = "7";
"IMON":   PN = "8"  !CDS_PN = "8";
"ISET":   PN = "5"  !CDS_PN = "5";
"LOADEN":   PN = "2"  !CDS_PN = "2";
"OV":   PN = "11"  !CDS_PN = "11";
"PG":   PN = "10"  !CDS_PN = "10";
"SS":   PN = "6"  !CDS_PN = "6";
"TIMER":   PN = "4"  !CDS_PN = "4";
"VIN_1":   PN = "21"  !CDS_PN = "21";
"VIN_2":   PN = "22"  !CDS_PN = "22";
"VIN_3":   PN = "23"  !CDS_PN = "23";
"VIN_4":   PN = "24"  !CDS_PN = "24";
"VIN_5":   PN = "25"  !CDS_PN = "25";
"VIN_6":   PN = "26"  !CDS_PN = "26";
"VOUT_1":   PN = "13"  !CDS_PN = "13";
"VOUT_2":   PN = "14"  !CDS_PN = "14";
"VOUT_3":   PN = "15"  !CDS_PN = "15";
"VOUT_4":   PN = "16"  !CDS_PN = "16";
"VOUT_5":   PN = "17"  !CDS_PN = "17";
"VOUT_6":   PN = "18"  !CDS_PN = "18";
"VOUT_7":   PN = "19"  !CDS_PN = "19";
"VOUT_8":   PN = "20"  !CDS_PN = "20";
BODY = "FUSE","I223": LOCATION = "FU1" #&CDS_LOCATION = "FU1" &SEC = "1" #&CDS_SEC = "1";
"1":   PN = "1"  !CDS_PN = "1";
"2":   PN = "2"  !CDS_PN = "2";
BODY = "CAPACITOR","I229": LOCATION = "C297" #&CDS_LOCATION = "C297" &SEC = "1" #&CDS_SEC = "1";
"1":   PN = "1"  !CDS_PN = "1";
"2":   PN = "2"  !CDS_PN = "2";
BODY = "CAPACITOR","I230": LOCATION = "C299" #&CDS_LOCATION = "C299" &SEC = "1" #&CDS_SEC = "1";
"1":   PN = "1"  !CDS_PN = "1";
"2":   PN = "2"  !CDS_PN = "2";
BODY = "CAPACITOR","I231": LOCATION = "C303" #&CDS_LOCATION = "C303" &SEC = "1" #&CDS_SEC = "1";
"1":   PN = "1"  !CDS_PN = "1";
"2":   PN = "2"  !CDS_PN = "2";
BODY = "CAPACITOR","I232": LOCATION = "C301" #&CDS_LOCATION = "C301" &SEC = "1" #&CDS_SEC = "1";
"1":   PN = "1"  !CDS_PN = "1";
"2":   PN = "2"  !CDS_PN = "2";
BODY = "CONN_HDR_2X3_M_RA_TH","I238": #LOCATION = "P3" !CDS_LOCATION = "P3" &SEC = "1" #&CDS_SEC = "1";
"1":   PN = "1"  !CDS_PN = "1";
"2":   PN = "2"  !CDS_PN = "2";
"3":   PN = "3"  !CDS_PN = "3";
"4":   PN = "4"  !CDS_PN = "4";
"5":   PN = "5"  !CDS_PN = "5";
"6":   PN = "6"  !CDS_PN = "6";
BODY = "DIODE_3F","I239": #LOCATION = "CR12" !CDS_LOCATION = "CR12" &SEC = "1" #&CDS_SEC = "1";
"A_1":   PN = "1"  !CDS_PN = "1";
"A_2":   PN = "2"  !CDS_PN = "2";
"C":   PN = "3"  !CDS_PN = "3";
BODY = "FERRITEBEAD","I240": #LOCATION = "L20" !CDS_LOCATION = "L20" &SEC = "1" #&CDS_SEC = "1";
"1":   PN = "1"  !CDS_PN = "1";
"2":   PN = "2"  !CDS_PN = "2";
DRAWING = "@timecard_lib.timecard(sch_1):page515";
BODY = "RESISTOR","I56": LOCATION = "R237" #&CDS_LOCATION = "R237" &SEC = "1" #&CDS_SEC = "1";
"1":   PN = "1"  !CDS_PN = "1";
"2":   PN = "2"  !CDS_PN = "2";
BODY = "CAPACITOR","I61": LOCATION = "C232" #&CDS_LOCATION = "C232" &SEC = "1" #&CDS_SEC = "1";
"1":   PN = "1"  !CDS_PN = "1";
"2":   PN = "2"  !CDS_PN = "2";
BODY = "CAPACITOR","I63": LOCATION = "C233" #&CDS_LOCATION = "C233" &SEC = "1" #&CDS_SEC = "1";
"1":   PN = "1"  !CDS_PN = "1";
"2":   PN = "2"  !CDS_PN = "2";
BODY = "CAPACITOR","I64": LOCATION = "C237" #&CDS_LOCATION = "C237" &SEC = "1" #&CDS_SEC = "1";
"1":   PN = "1"  !CDS_PN = "1";
"2":   PN = "2"  !CDS_PN = "2";
BODY = "CAPACITOR","I66": LOCATION = "C236" #&CDS_LOCATION = "C236" &SEC = "1" #&CDS_SEC = "1";
"1":   PN = "1"  !CDS_PN = "1";
"2":   PN = "2"  !CDS_PN = "2";
BODY = "RESISTOR","I67": LOCATION = "R260" #&CDS_LOCATION = "R260" &SEC = "1" #&CDS_SEC = "1";
"1":   PN = "1"  !CDS_PN = "1";
"2":   PN = "2"  !CDS_PN = "2";
BODY = "RESISTOR","I69": LOCATION = "R295" #&CDS_LOCATION = "R295" &SEC = "1" #&CDS_SEC = "1";
"1":   PN = "1"  !CDS_PN = "1";
"2":   PN = "2"  !CDS_PN = "2";
BODY = "CAPACITOR","I71": LOCATION = "C240" #&CDS_LOCATION = "C240" &SEC = "1" #&CDS_SEC = "1";
"1":   PN = "1"  !CDS_PN = "1";
"2":   PN = "2"  !CDS_PN = "2";
BODY = "CAPACITOR","I72": LOCATION = "C241" #&CDS_LOCATION = "C241" &SEC = "1" #&CDS_SEC = "1";
"1":   PN = "1"  !CDS_PN = "1";
"2":   PN = "2"  !CDS_PN = "2";
BODY = "CAPACITOR","I74": LOCATION = "C243" #&CDS_LOCATION = "C243" &SEC = "1" #&CDS_SEC = "1";
"1":   PN = "1"  !CDS_PN = "1";
"2":   PN = "2"  !CDS_PN = "2";
BODY = "NCP45560IMNTWG_H_DFN12","I76": LOCATION = "U22" #&CDS_LOCATION = "U22" &SEC = "2" #&CDS_SEC = "2";
"GND":   PN = "4"  !CDS_PN = "4";
"VCC":   PN = "3"  !CDS_PN = "3";
BODY = "CAPACITOR","I80": LOCATION = "C235" #&CDS_LOCATION = "C235" &SEC = "1" #&CDS_SEC = "1";
"1":   PN = "1"  !CDS_PN = "1";
"2":   PN = "2"  !CDS_PN = "2";
BODY = "CAPACITOR","I81": LOCATION = "C238" #&CDS_LOCATION = "C238" &SEC = "1" #&CDS_SEC = "1";
"1":   PN = "1"  !CDS_PN = "1";
"2":   PN = "2"  !CDS_PN = "2";
BODY = "NCP45560IMNTWG_H_DFN12","I82": LOCATION = "U22" #&CDS_LOCATION = "U22" &SEC = "1" #&CDS_SEC = "1";
"BLEED":   PN = "7"  !CDS_PN = "7";
"EN":   PN = "2"  !CDS_PN = "2";
"PG":   PN = "6"  !CDS_PN = "6";
"SR":   PN = "5"  !CDS_PN = "5";
"VIN_1":   PN = "1"  !CDS_PN = "1";
"VIN_2":   PN = "13"  !CDS_PN = "13";
"VOUT_1":   PN = "8"  !CDS_PN = "8";
"VOUT_2":   PN = "9"  !CDS_PN = "9";
"VOUT_3":   PN = "10"  !CDS_PN = "10";
"VOUT_4":   PN = "11"  !CDS_PN = "11";
"VOUT_5":   PN = "12"  !CDS_PN = "12";
BODY = "CAPACITOR","I87": LOCATION = "C229" #&CDS_LOCATION = "C229" &SEC = "1" #&CDS_SEC = "1";
"1":   PN = "1"  !CDS_PN = "1";
"2":   PN = "2"  !CDS_PN = "2";
BODY = "RESISTOR","I122": LOCATION = "R226" #&CDS_LOCATION = "R226" &SEC = "1" #&CDS_SEC = "1";
"1":   PN = "1"  !CDS_PN = "1";
"2":   PN = "2"  !CDS_PN = "2";
BODY = "RESISTOR","I127": LOCATION = "R227" #&CDS_LOCATION = "R227" &SEC = "1" #&CDS_SEC = "1";
"1":   PN = "1"  !CDS_PN = "1";
"2":   PN = "2"  !CDS_PN = "2";
BODY = "CAPACITOR","I128": LOCATION = "C227" #&CDS_LOCATION = "C227" &SEC = "1" #&CDS_SEC = "1";
"1":   PN = "1"  !CDS_PN = "1";
"2":   PN = "2"  !CDS_PN = "2";
BODY = "RESISTOR","I129": LOCATION = "R228" #&CDS_LOCATION = "R228" &SEC = "1" #&CDS_SEC = "1";
"1":   PN = "1"  !CDS_PN = "1";
"2":   PN = "2"  !CDS_PN = "2";
BODY = "CAPACITOR","I130": LOCATION = "C228" #&CDS_LOCATION = "C228" &SEC = "1" #&CDS_SEC = "1";
"1":   PN = "1"  !CDS_PN = "1";
"2":   PN = "2"  !CDS_PN = "2";
BODY = "CAPACITOR","I132": LOCATION = "C231" #&CDS_LOCATION = "C231" &SEC = "1" #&CDS_SEC = "1";
"1":   PN = "1"  !CDS_PN = "1";
"2":   PN = "2"  !CDS_PN = "2";
BODY = "CAPACITOR","I134": LOCATION = "C230" #&CDS_LOCATION = "C230" &SEC = "1" #&CDS_SEC = "1";
"1":   PN = "1"  !CDS_PN = "1";
"2":   PN = "2"  !CDS_PN = "2";
BODY = "FERRITEBEAD","I135": LOCATION = "L13" #&CDS_LOCATION = "L13" &SEC = "1" #&CDS_SEC = "1";
"1":   PN = "1"  !CDS_PN = "1";
"2":   PN = "2"  !CDS_PN = "2";
BODY = "CAPACITOR","I138": LOCATION = "C234" #&CDS_LOCATION = "C234" &SEC = "1" #&CDS_SEC = "1";
"1":   PN = "1"  !CDS_PN = "1";
"2":   PN = "2"  !CDS_PN = "2";
BODY = "RESISTOR","I139": LOCATION = "R229" #&CDS_LOCATION = "R229" &SEC = "1" #&CDS_SEC = "1";
"1":   PN = "1"  !CDS_PN = "1";
"2":   PN = "2"  !CDS_PN = "2";
BODY = "RESISTOR","I140": LOCATION = "R230" #&CDS_LOCATION = "R230" &SEC = "1" #&CDS_SEC = "1";
"1":   PN = "1"  !CDS_PN = "1";
"2":   PN = "2"  !CDS_PN = "2";
BODY = "RESISTOR","I143": LOCATION = "R232" #&CDS_LOCATION = "R232" &SEC = "1" #&CDS_SEC = "1";
"1":   PN = "1"  !CDS_PN = "1";
"2":   PN = "2"  !CDS_PN = "2";
BODY = "RESISTOR","I145": LOCATION = "R233" #&CDS_LOCATION = "R233" &SEC = "1" #&CDS_SEC = "1";
"1":   PN = "1"  !CDS_PN = "1";
"2":   PN = "2"  !CDS_PN = "2";
BODY = "RESISTOR","I146": LOCATION = "R231" #&CDS_LOCATION = "R231" &SEC = "1" #&CDS_SEC = "1";
"1":   PN = "1"  !CDS_PN = "1";
"2":   PN = "2"  !CDS_PN = "2";
BODY = "CAPACITOR","I147": LOCATION = "C239" #&CDS_LOCATION = "C239" &SEC = "1" #&CDS_SEC = "1";
"1":   PN = "1"  !CDS_PN = "1";
"2":   PN = "2"  !CDS_PN = "2";
BODY = "CAPACITOR","I149": LOCATION = "C242" #&CDS_LOCATION = "C242" &SEC = "1" #&CDS_SEC = "1";
"1":   PN = "1"  !CDS_PN = "1";
"2":   PN = "2"  !CDS_PN = "2";
BODY = "ISL80101IRAJZ_DFN10","I151": LOCATION = "U25" #&CDS_LOCATION = "U25" &SEC = "1" #&CDS_SEC = "1";
"ENABLE":   PN = "7"  !CDS_PN = "7";
"GND":   PN = "5"  !CDS_PN = "5";
"NC":   PN = "8"  !CDS_PN = "8";
"PG":   PN = "4"  !CDS_PN = "4";
"SENSE/ADJ":   PN = "3"  !CDS_PN = "3";
"SS":   PN = "6"  !CDS_PN = "6";
"THRM_PAD":   PN = "11"  !CDS_PN = "11";
"VIN_1":   PN = "9"  !CDS_PN = "9";
"VIN_2":   PN = "10"  !CDS_PN = "10";
"VOUT_1":   PN = "1"  !CDS_PN = "1";
"VOUT_2":   PN = "2"  !CDS_PN = "2";
BODY = "RESISTOR","I152": LOCATION = "R225" #&CDS_LOCATION = "R225" &SEC = "1" #&CDS_SEC = "1";
"1":   PN = "1"  !CDS_PN = "1";
"2":   PN = "2"  !CDS_PN = "2";
BODY = "CAPACITOR","I154": LOCATION = "C224" #&CDS_LOCATION = "C224" &SEC = "1" #&CDS_SEC = "1";
"1":   PN = "1"  !CDS_PN = "1";
"2":   PN = "2"  !CDS_PN = "2";
BODY = "CAPACITOR","I155": LOCATION = "C226" #&CDS_LOCATION = "C226" &SEC = "1" #&CDS_SEC = "1";
"1":   PN = "1"  !CDS_PN = "1";
"2":   PN = "2"  !CDS_PN = "2";
BODY = "RESISTOR","I167": LOCATION = "R143" #&CDS_LOCATION = "R143" &SEC = "1" #&CDS_SEC = "1";
"1":   PN = "1"  !CDS_PN = "1";
"2":   PN = "2"  !CDS_PN = "2";
BODY = "CAPACITOR","I168": LOCATION = "C293" #&CDS_LOCATION = "C293" &SEC = "1" #&CDS_SEC = "1";
"1":   PN = "1"  !CDS_PN = "1";
"2":   PN = "2"  !CDS_PN = "2";
BODY = "CAPACITOR","I169": LOCATION = "C294" #&CDS_LOCATION = "C294" &SEC = "1" #&CDS_SEC = "1";
"1":   PN = "1"  !CDS_PN = "1";
"2":   PN = "2"  !CDS_PN = "2";
DRAWING = "@timecard_lib.timecard(sch_1):page523";
BODY = "CAPACITOR","I7": LOCATION = "C256" #&CDS_LOCATION = "C256" &SEC = "1" #&CDS_SEC = "1";
"1":   PN = "1"  !CDS_PN = "1";
"2":   PN = "2"  !CDS_PN = "2";
BODY = "CAPACITOR","I9": LOCATION = "C263" #&CDS_LOCATION = "C263" &SEC = "1" #&CDS_SEC = "1";
"1":   PN = "1"  !CDS_PN = "1";
"2":   PN = "2"  !CDS_PN = "2";
BODY = "CAPACITOR","I10": LOCATION = "C264" #&CDS_LOCATION = "C264" &SEC = "1" #&CDS_SEC = "1";
"1":   PN = "1"  !CDS_PN = "1";
"2":   PN = "2"  !CDS_PN = "2";
BODY = "TPS54824RNVR_VQFN18","I11": LOCATION = "U26" #&CDS_LOCATION = "U26" &SEC = "1" #&CDS_SEC = "1";
"AGND":   PN = "12"  !CDS_PN = "12";
"BOOT":   PN = "1"  !CDS_PN = "1";
"COMP":   PN = "15"  !CDS_PN = "15";
"EN":   PN = "17"  !CDS_PN = "17";
"FB":   PN = "14"  !CDS_PN = "14";
"PGND_1":   PN = "3"  !CDS_PN = "3";
"PGND_2":   PN = "4"  !CDS_PN = "4";
"PGND_3":   PN = "5"  !CDS_PN = "5";
"PGND_4":   PN = "8"  !CDS_PN = "8";
"PGND_5":   PN = "9"  !CDS_PN = "9";
"PGND_6":   PN = "10"  !CDS_PN = "10";
"PGOOD":   PN = "18"  !CDS_PN = "18";
"RT/CLK":   PN = "13"  !CDS_PN = "13";
"SS/TRK":   PN = "16"  !CDS_PN = "16";
"SW_1":   PN = "6"  !CDS_PN = "6";
"SW_2":   PN = "7"  !CDS_PN = "7";
"VIN_1":   PN = "2"  !CDS_PN = "2";
"VIN_2":   PN = "11"  !CDS_PN = "11";
BODY = "CAPACITOR","I12": LOCATION = "C259" #&CDS_LOCATION = "C259" &SEC = "1" #&CDS_SEC = "1";
"1":   PN = "1"  !CDS_PN = "1";
"2":   PN = "2"  !CDS_PN = "2";
BODY = "CAPACITOR","I13": LOCATION = "C257" #&CDS_LOCATION = "C257" &SEC = "1" #&CDS_SEC = "1";
"1":   PN = "1"  !CDS_PN = "1";
"2":   PN = "2"  !CDS_PN = "2";
BODY = "CAPACITOR","I14": LOCATION = "C260" #&CDS_LOCATION = "C260" &SEC = "1" #&CDS_SEC = "1";
"1":   PN = "1"  !CDS_PN = "1";
"2":   PN = "2"  !CDS_PN = "2";
BODY = "RESISTOR","I15": LOCATION = "R248" #&CDS_LOCATION = "R248" &SEC = "1" #&CDS_SEC = "1";
"1":   PN = "1"  !CDS_PN = "1";
"2":   PN = "2"  !CDS_PN = "2";
BODY = "RESISTOR","I16": LOCATION = "R249" #&CDS_LOCATION = "R249" &SEC = "1" #&CDS_SEC = "1";
"1":   PN = "1"  !CDS_PN = "1";
"2":   PN = "2"  !CDS_PN = "2";
BODY = "CAPACITOR","I17": LOCATION = "C261" #&CDS_LOCATION = "C261" &SEC = "1" #&CDS_SEC = "1";
"1":   PN = "1"  !CDS_PN = "1";
"2":   PN = "2"  !CDS_PN = "2";
BODY = "CAPACITOR","I19": LOCATION = "C262" #&CDS_LOCATION = "C262" &SEC = "1" #&CDS_SEC = "1";
"1":   PN = "1"  !CDS_PN = "1";
"2":   PN = "2"  !CDS_PN = "2";
BODY = "RESISTOR","I23": LOCATION = "R250" #&CDS_LOCATION = "R250" &SEC = "1" #&CDS_SEC = "1";
"1":   PN = "1"  !CDS_PN = "1";
"2":   PN = "2"  !CDS_PN = "2";
BODY = "CAPACITOR","I24": LOCATION = "C265" #&CDS_LOCATION = "C265" &SEC = "1" #&CDS_SEC = "1";
"1":   PN = "1"  !CDS_PN = "1";
"2":   PN = "2"  !CDS_PN = "2";
BODY = "INDUCTOR_2","I25": LOCATION = "L5" #&CDS_LOCATION = "L5" &SEC = "1" #&CDS_SEC = "1";
"1":   PN = "1"  !CDS_PN = "1";
"2":   PN = "2"  !CDS_PN = "2";
BODY = "RESISTOR","I26": LOCATION = "R253" #&CDS_LOCATION = "R253" &SEC = "1" #&CDS_SEC = "1";
"1":   PN = "1"  !CDS_PN = "1";
"2":   PN = "2"  !CDS_PN = "2";
BODY = "CAPACITOR","I28": LOCATION = "C267" #&CDS_LOCATION = "C267" &SEC = "1" #&CDS_SEC = "1";
"1":   PN = "1"  !CDS_PN = "1";
"2":   PN = "2"  !CDS_PN = "2";
BODY = "RESISTOR","I29": LOCATION = "R255" #&CDS_LOCATION = "R255" &SEC = "1" #&CDS_SEC = "1";
"1":   PN = "1"  !CDS_PN = "1";
"2":   PN = "2"  !CDS_PN = "2";
BODY = "RESISTOR","I30": LOCATION = "R254" #&CDS_LOCATION = "R254" &SEC = "1" #&CDS_SEC = "1";
"1":   PN = "1"  !CDS_PN = "1";
"2":   PN = "2"  !CDS_PN = "2";
BODY = "CAPACITOR","I31": LOCATION = "C266" #&CDS_LOCATION = "C266" &SEC = "1" #&CDS_SEC = "1";
"1":   PN = "1"  !CDS_PN = "1";
"2":   PN = "2"  !CDS_PN = "2";
BODY = "CAPACITOR","I33": LOCATION = "C268" #&CDS_LOCATION = "C268" &SEC = "1" #&CDS_SEC = "1";
"1":   PN = "1"  !CDS_PN = "1";
"2":   PN = "2"  !CDS_PN = "2";
BODY = "CAPACITOR","I34": LOCATION = "C269" #&CDS_LOCATION = "C269" &SEC = "1" #&CDS_SEC = "1";
"1":   PN = "1"  !CDS_PN = "1";
"2":   PN = "2"  !CDS_PN = "2";
BODY = "CAPACITOR","I35": LOCATION = "C270" #&CDS_LOCATION = "C270" &SEC = "1" #&CDS_SEC = "1";
"1":   PN = "1"  !CDS_PN = "1";
"2":   PN = "2"  !CDS_PN = "2";
BODY = "CAPACITOR","I37": LOCATION = "C271" #&CDS_LOCATION = "C271" &SEC = "1" #&CDS_SEC = "1";
"1":   PN = "1"  !CDS_PN = "1";
"2":   PN = "2"  !CDS_PN = "2";
BODY = "SOLDER_PREFORM","I39": LOCATION = "SP3" #&CDS_LOCATION = "SP3" &SEC = "1" #&CDS_SEC = "1";
"1":   PN = "1"  !CDS_PN = "1";
"2":   PN = "2"  !CDS_PN = "2";
BODY = "RESISTOR","I44": LOCATION = "R243" #&CDS_LOCATION = "R243" &SEC = "1" #&CDS_SEC = "1";
"1":   PN = "1"  !CDS_PN = "1";
"2":   PN = "2"  !CDS_PN = "2";
BODY = "CAPACITOR","I46": LOCATION = "C255" #&CDS_LOCATION = "C255" &SEC = "1" #&CDS_SEC = "1";
"1":   PN = "1"  !CDS_PN = "1";
"2":   PN = "2"  !CDS_PN = "2";
BODY = "FERRITEBEAD","I48": LOCATION = "L9" #&CDS_LOCATION = "L9" &SEC = "1" #&CDS_SEC = "1";
"1":   PN = "1"  !CDS_PN = "1";
"2":   PN = "2"  !CDS_PN = "2";
BODY = "CAPACITOR","I50": LOCATION = "C258" #&CDS_LOCATION = "C258" &SEC = "1" #&CDS_SEC = "1";
"1":   PN = "1"  !CDS_PN = "1";
"2":   PN = "2"  !CDS_PN = "2";
BODY = "RESISTOR","I51": LOCATION = "R246" #&CDS_LOCATION = "R246" &SEC = "1" #&CDS_SEC = "1";
"1":   PN = "1"  !CDS_PN = "1";
"2":   PN = "2"  !CDS_PN = "2";
BODY = "RESISTOR","I54": LOCATION = "R247" #&CDS_LOCATION = "R247" &SEC = "1" #&CDS_SEC = "1";
"1":   PN = "1"  !CDS_PN = "1";
"2":   PN = "2"  !CDS_PN = "2";
BODY = "RESISTOR","I56": LOCATION = "R251" #&CDS_LOCATION = "R251" &SEC = "1" #&CDS_SEC = "1";
"1":   PN = "1"  !CDS_PN = "1";
"2":   PN = "2"  !CDS_PN = "2";
BODY = "RESISTOR","I57": LOCATION = "R252" #&CDS_LOCATION = "R252" &SEC = "1" #&CDS_SEC = "1";
"1":   PN = "1"  !CDS_PN = "1";
"2":   PN = "2"  !CDS_PN = "2";
BODY = "RESISTOR","I104": LOCATION = "R245" #&CDS_LOCATION = "R245" &SEC = "1" #&CDS_SEC = "1";
"1":   PN = "1"  !CDS_PN = "1";
"2":   PN = "2"  !CDS_PN = "2";
BODY = "RESISTOR","I109": LOCATION = "R244" #&CDS_LOCATION = "R244" &SEC = "1" #&CDS_SEC = "1";
"1":   PN = "1"  !CDS_PN = "1";
"2":   PN = "2"  !CDS_PN = "2";
DRAWING = "@timecard_lib.timecard(sch_1):page8";
BODY = "RESISTOR","I3": LOCATION = "R70" #&CDS_LOCATION = "R70" &SEC = "1" #&CDS_SEC = "1";
"1":   PN = "1"  !CDS_PN = "1";
"2":   PN = "2"  !CDS_PN = "2";
BODY = "RESISTOR","I5": LOCATION = "R71" #&CDS_LOCATION = "R71" &SEC = "1" #&CDS_SEC = "1";
"1":   PN = "1"  !CDS_PN = "1";
"2":   PN = "2"  !CDS_PN = "2";
BODY = "RESISTOR","I6": LOCATION = "R73" #&CDS_LOCATION = "R73" &SEC = "1" #&CDS_SEC = "1";
"1":   PN = "1"  !CDS_PN = "1";
"2":   PN = "2"  !CDS_PN = "2";
BODY = "RESISTOR","I7": LOCATION = "R72" #&CDS_LOCATION = "R72" &SEC = "1" #&CDS_SEC = "1";
"1":   PN = "1"  !CDS_PN = "1";
"2":   PN = "2"  !CDS_PN = "2";
BODY = "CAPACITOR","I16": LOCATION = "C276" #&CDS_LOCATION = "C276" &SEC = "1" #&CDS_SEC = "1";
"1":   PN = "1"  !CDS_PN = "1";
"2":   PN = "2"  !CDS_PN = "2";
BODY = "FERRITEBEAD","I18": LOCATION = "L18" #&CDS_LOCATION = "L18" &SEC = "1" #&CDS_SEC = "1";
"1":   PN = "1"  !CDS_PN = "1";
"2":   PN = "2"  !CDS_PN = "2";
BODY = "CAPACITOR","I19": LOCATION = "C278" #&CDS_LOCATION = "C278" &SEC = "1" #&CDS_SEC = "1";
"1":   PN = "1"  !CDS_PN = "1";
"2":   PN = "2"  !CDS_PN = "2";
BODY = "CAPACITOR","I21": LOCATION = "C277" #&CDS_LOCATION = "C277" &SEC = "1" #&CDS_SEC = "1";
"1":   PN = "1"  !CDS_PN = "1";
"2":   PN = "2"  !CDS_PN = "2";
BODY = "ICP_10100_LGA10","I24": LOCATION = "U28" #&CDS_LOCATION = "U28" &SEC = "1" #&CDS_SEC = "1";
"GND_1":   PN = "8"  !CDS_PN = "8";
"GND_2":   PN = "9"  !CDS_PN = "9";
"RESV_1":   PN = "1"  !CDS_PN = "1";
"RESV_2":   PN = "3"  !CDS_PN = "3";
"RESV_3":   PN = "5"  !CDS_PN = "5";
"RESV_4":   PN = "6"  !CDS_PN = "6";
"RESV_5":   PN = "7"  !CDS_PN = "7";
"SCL":   PN = "2"  !CDS_PN = "2";
"SDA":   PN = "4"  !CDS_PN = "4";
"VDD":   PN = "10"  !CDS_PN = "10";
BODY = "RESISTOR","I30": LOCATION = "R351" #&CDS_LOCATION = "R351" &SEC = "1" #&CDS_SEC = "1";
"1":   PN = "1"  !CDS_PN = "1";
"2":   PN = "2"  !CDS_PN = "2";
BODY = "RESISTOR","I31": #LOCATION = "R350" !CDS_LOCATION = "R350" &SEC = "1" #&CDS_SEC = "1";
"1":   PN = "1"  !CDS_PN = "1";
"2":   PN = "2"  !CDS_PN = "2";
BODY = "RESISTOR","I32": #LOCATION = "R347" !CDS_LOCATION = "R347" &SEC = "1" #&CDS_SEC = "1";
"1":   PN = "1"  !CDS_PN = "1";
"2":   PN = "2"  !CDS_PN = "2";
BODY = "RESISTOR","I33": #LOCATION = "R346" !CDS_LOCATION = "R346" &SEC = "1" #&CDS_SEC = "1";
"1":   PN = "1"  !CDS_PN = "1";
"2":   PN = "2"  !CDS_PN = "2";
BODY = "RESISTOR","I34": #LOCATION = "R343" !CDS_LOCATION = "R343" &SEC = "1" #&CDS_SEC = "1";
"1":   PN = "1"  !CDS_PN = "1";
"2":   PN = "2"  !CDS_PN = "2";
BODY = "CAPACITOR","I39": LOCATION = "C312" #&CDS_LOCATION = "C312" &SEC = "1" #&CDS_SEC = "1";
"1":   PN = "1"  !CDS_PN = "1";
"2":   PN = "2"  !CDS_PN = "2";
BODY = "CAPACITOR","I41": LOCATION = "C313" #&CDS_LOCATION = "C313" &SEC = "1" #&CDS_SEC = "1";
"1":   PN = "1"  !CDS_PN = "1";
"2":   PN = "2"  !CDS_PN = "2";
BODY = "PCA9508DP_TSSOP8","I51": LOCATION = "U32" #&CDS_LOCATION = "U32" &SEC = "1" #&CDS_SEC = "1";
"EN":   PN = "5"  !CDS_PN = "5";
"SCLA":   PN = "2"  !CDS_PN = "2";
"SCLB":   PN = "7"  !CDS_PN = "7";
"SDAA":   PN = "3"  !CDS_PN = "3";
"SDAB":   PN = "6"  !CDS_PN = "6";
BODY = "PCA9508DP_TSSOP8","I52": LOCATION = "U32" #&CDS_LOCATION = "U32" &SEC = "2" #&CDS_SEC = "2";
"GND":   PN = "4"  !CDS_PN = "4";
"VCC_A":   PN = "1"  !CDS_PN = "1";
"VCC_B":   PN = "8"  !CDS_PN = "8";
BODY = "RESISTOR","I63": LOCATION = "R315" #&CDS_LOCATION = "R315" &SEC = "1" #&CDS_SEC = "1";
"1":   PN = "1"  !CDS_PN = "1";
"2":   PN = "2"  !CDS_PN = "2";
BODY = "RESISTOR","I64": LOCATION = "R316" #&CDS_LOCATION = "R316" &SEC = "1" #&CDS_SEC = "1";
"1":   PN = "1"  !CDS_PN = "1";
"2":   PN = "2"  !CDS_PN = "2";
BODY = "RESISTOR","I69": LOCATION = "R282" #&CDS_LOCATION = "R282" &SEC = "1" #&CDS_SEC = "1";
"1":   PN = "1"  !CDS_PN = "1";
"2":   PN = "2"  !CDS_PN = "2";
BODY = "RESISTOR","I70": LOCATION = "R281" #&CDS_LOCATION = "R281" &SEC = "1" #&CDS_SEC = "1";
"1":   PN = "1"  !CDS_PN = "1";
"2":   PN = "2"  !CDS_PN = "2";
BODY = "RESISTOR","I71": LOCATION = "R314" #&CDS_LOCATION = "R314" &SEC = "1" #&CDS_SEC = "1";
"1":   PN = "1"  !CDS_PN = "1";
"2":   PN = "2"  !CDS_PN = "2";
DRAWING = "@timecard_lib.timecard(sch_1):page127";
BODY = "XC7A200T_2FBG484C_FBG484","I232": LOCATION = "U24" #&CDS_LOCATION = "U24" &SEC = "1" #&CDS_SEC = "1";
"CCLK_0":   PN = "L12"  !CDS_PN = "L12";
"CFGBVS_0":   PN = "U8"  !CDS_PN = "U8";
"DONE_0":   PN = "G11"  !CDS_PN = "G11";
"DXN_0":   PN = "N9"  !CDS_PN = "N9";
"DXP_0":   PN = "N10"  !CDS_PN = "N10";
"INIT_0*":   PN = "U12"  !CDS_PN = "U12";
"M0_0":   PN = "U11"  !CDS_PN = "U11";
"M1_0":   PN = "U10"  !CDS_PN = "U10";
"M2_0":   PN = "U9"  !CDS_PN = "U9";
"MGTPRXN0_216":   PN = "A8"  !CDS_PN = "A8";
"MGTPRXN1_216":   PN = "C11"  !CDS_PN = "C11";
"MGTPRXN2_216":   PN = "A10"  !CDS_PN = "A10";
"MGTPRXN3_216":   PN = "C9"  !CDS_PN = "C9";
"MGTPRXP0_216":   PN = "B8"  !CDS_PN = "B8";
"MGTPRXP1_216":   PN = "D11"  !CDS_PN = "D11";
"MGTPRXP2_216":   PN = "B10"  !CDS_PN = "B10";
"MGTPRXP3_216":   PN = "D9"  !CDS_PN = "D9";
"MGTPTXN0_216":   PN = "A4"  !CDS_PN = "A4";
"MGTPTXN1_216":   PN = "C5"  !CDS_PN = "C5";
"MGTPTXN2_216":   PN = "A6"  !CDS_PN = "A6";
"MGTPTXN3_216":   PN = "C7"  !CDS_PN = "C7";
"MGTPTXP0_216":   PN = "B4"  !CDS_PN = "B4";
"MGTPTXP1_216":   PN = "D5"  !CDS_PN = "D5";
"MGTPTXP2_216":   PN = "B6"  !CDS_PN = "B6";
"MGTPTXP3_216":   PN = "D7"  !CDS_PN = "D7";
"MGTREFCLK0N_216":   PN = "E6"  !CDS_PN = "E6";
"MGTREFCLK0P_216":   PN = "F6"  !CDS_PN = "F6";
"MGTREFCLK1N_216":   PN = "E10"  !CDS_PN = "E10";
"MGTREFCLK1P_216":   PN = "F10"  !CDS_PN = "F10";
"MGTRREF_216":   PN = "F8"  !CDS_PN = "F8";
"PROGRAM_0*":   PN = "N12"  !CDS_PN = "N12";
"TCK_0":   PN = "V12"  !CDS_PN = "V12";
"TDI_0":   PN = "R13"  !CDS_PN = "R13";
"TDO_0":   PN = "U13"  !CDS_PN = "U13";
"TMS_0":   PN = "T13"  !CDS_PN = "T13";
"VN_0":   PN = "M9"  !CDS_PN = "M9";
"VP_0":   PN = "L10"  !CDS_PN = "L10";
"VREFN_0":   PN = "L9"  !CDS_PN = "L9";
"VREFP_0":   PN = "M10"  !CDS_PN = "M10";
BODY = "RESISTOR","I329": LOCATION = "R194" #&CDS_LOCATION = "R194" &SEC = "1" #&CDS_SEC = "1";
"1":   PN = "1"  !CDS_PN = "1";
"2":   PN = "2"  !CDS_PN = "2";
BODY = "RESISTOR","I330": LOCATION = "R193" #&CDS_LOCATION = "R193" &SEC = "1" #&CDS_SEC = "1";
"1":   PN = "1"  !CDS_PN = "1";
"2":   PN = "2"  !CDS_PN = "2";
BODY = "RESISTOR","I331": LOCATION = "R195" #&CDS_LOCATION = "R195" &SEC = "1" #&CDS_SEC = "1";
"1":   PN = "1"  !CDS_PN = "1";
"2":   PN = "2"  !CDS_PN = "2";
BODY = "RESISTOR","I332": LOCATION = "R196" #&CDS_LOCATION = "R196" &SEC = "1" #&CDS_SEC = "1";
"1":   PN = "1"  !CDS_PN = "1";
"2":   PN = "2"  !CDS_PN = "2";
BODY = "RESISTOR","I333": LOCATION = "R197" #&CDS_LOCATION = "R197" &SEC = "1" #&CDS_SEC = "1";
"1":   PN = "1"  !CDS_PN = "1";
"2":   PN = "2"  !CDS_PN = "2";
BODY = "RESISTOR","I334": LOCATION = "R198" #&CDS_LOCATION = "R198" &SEC = "1" #&CDS_SEC = "1";
"1":   PN = "1"  !CDS_PN = "1";
"2":   PN = "2"  !CDS_PN = "2";
BODY = "RESISTOR","I337": LOCATION = "R207" #&CDS_LOCATION = "R207" &SEC = "1" #&CDS_SEC = "1";
"1":   PN = "1"  !CDS_PN = "1";
"2":   PN = "2"  !CDS_PN = "2";
BODY = "RESISTOR","I338": LOCATION = "R210" #&CDS_LOCATION = "R210" &SEC = "1" #&CDS_SEC = "1";
"1":   PN = "1"  !CDS_PN = "1";
"2":   PN = "2"  !CDS_PN = "2";
BODY = "RESISTOR","I339": LOCATION = "R209" #&CDS_LOCATION = "R209" &SEC = "1" #&CDS_SEC = "1";
"1":   PN = "1"  !CDS_PN = "1";
"2":   PN = "2"  !CDS_PN = "2";
BODY = "RESISTOR","I391": LOCATION = "R216" #&CDS_LOCATION = "R216" &SEC = "1" #&CDS_SEC = "1";
"1":   PN = "1"  !CDS_PN = "1";
"2":   PN = "2"  !CDS_PN = "2";
BODY = "RESISTOR","I392": LOCATION = "R219" #&CDS_LOCATION = "R219" &SEC = "1" #&CDS_SEC = "1";
"1":   PN = "1"  !CDS_PN = "1";
"2":   PN = "2"  !CDS_PN = "2";
BODY = "RESISTOR","I393": LOCATION = "R220" #&CDS_LOCATION = "R220" &SEC = "1" #&CDS_SEC = "1";
"1":   PN = "1"  !CDS_PN = "1";
"2":   PN = "2"  !CDS_PN = "2";
BODY = "RESISTOR","I394": LOCATION = "R215" #&CDS_LOCATION = "R215" &SEC = "1" #&CDS_SEC = "1";
"1":   PN = "1"  !CDS_PN = "1";
"2":   PN = "2"  !CDS_PN = "2";
BODY = "RESISTOR","I396": LOCATION = "R213" #&CDS_LOCATION = "R213" &SEC = "1" #&CDS_SEC = "1";
"1":   PN = "1"  !CDS_PN = "1";
"2":   PN = "2"  !CDS_PN = "2";
BODY = "RESISTOR","I397": LOCATION = "R214" #&CDS_LOCATION = "R214" &SEC = "1" #&CDS_SEC = "1";
"1":   PN = "1"  !CDS_PN = "1";
"2":   PN = "2"  !CDS_PN = "2";
BODY = "RESISTOR","I402": LOCATION = "R217" #&CDS_LOCATION = "R217" &SEC = "1" #&CDS_SEC = "1";
"1":   PN = "1"  !CDS_PN = "1";
"2":   PN = "2"  !CDS_PN = "2";
BODY = "RESISTOR","I403": LOCATION = "R221" #&CDS_LOCATION = "R221" &SEC = "1" #&CDS_SEC = "1";
"1":   PN = "1"  !CDS_PN = "1";
"2":   PN = "2"  !CDS_PN = "2";
BODY = "RESISTOR","I404": LOCATION = "R211" #&CDS_LOCATION = "R211" &SEC = "1" #&CDS_SEC = "1";
"1":   PN = "1"  !CDS_PN = "1";
"2":   PN = "2"  !CDS_PN = "2";
BODY = "RESISTOR","I405": LOCATION = "R222" #&CDS_LOCATION = "R222" &SEC = "1" #&CDS_SEC = "1";
"1":   PN = "1"  !CDS_PN = "1";
"2":   PN = "2"  !CDS_PN = "2";
BODY = "RESISTOR","I406": LOCATION = "R218" #&CDS_LOCATION = "R218" &SEC = "1" #&CDS_SEC = "1";
"1":   PN = "1"  !CDS_PN = "1";
"2":   PN = "2"  !CDS_PN = "2";
BODY = "RESISTOR","I407": LOCATION = "R212" #&CDS_LOCATION = "R212" &SEC = "1" #&CDS_SEC = "1";
"1":   PN = "1"  !CDS_PN = "1";
"2":   PN = "2"  !CDS_PN = "2";
BODY = "G200_10283_01","I427": LOCATION = "J14" #&CDS_LOCATION = "J14" &SEC = "1" #&CDS_SEC = "1";
"1":   PN = "1"  !CDS_PN = "1";
"2":   PN = "2"  !CDS_PN = "2";
"3":   PN = "3"  !CDS_PN = "3";
"4":   PN = "4"  !CDS_PN = "4";
"5":   PN = "5"  !CDS_PN = "5";
"6":   PN = "6"  !CDS_PN = "6";
"7":   PN = "7"  !CDS_PN = "7";
"8":   PN = "8"  !CDS_PN = "8";
"9":   PN = "9"  !CDS_PN = "9";
"10":   PN = "10"  !CDS_PN = "10";
BODY = "RESISTOR","I432": LOCATION = "R405" #&CDS_LOCATION = "R405" &SEC = "1" #&CDS_SEC = "1";
"1":   PN = "1"  !CDS_PN = "1";
"2":   PN = "2"  !CDS_PN = "2";
BODY = "RESISTOR","I434": LOCATION = "R404" #&CDS_LOCATION = "R404" &SEC = "1" #&CDS_SEC = "1";
"1":   PN = "1"  !CDS_PN = "1";
"2":   PN = "2"  !CDS_PN = "2";
BODY = "RESISTOR","I435": LOCATION = "R403" #&CDS_LOCATION = "R403" &SEC = "1" #&CDS_SEC = "1";
"1":   PN = "1"  !CDS_PN = "1";
"2":   PN = "2"  !CDS_PN = "2";
BODY = "RESISTOR","I436": LOCATION = "R134" #&CDS_LOCATION = "R134" &SEC = "1" #&CDS_SEC = "1";
"1":   PN = "1"  !CDS_PN = "1";
"2":   PN = "2"  !CDS_PN = "2";
BODY = "RESISTOR","I437": LOCATION = "R136" #&CDS_LOCATION = "R136" &SEC = "1" #&CDS_SEC = "1";
"1":   PN = "1"  !CDS_PN = "1";
"2":   PN = "2"  !CDS_PN = "2";
BODY = "RESISTOR","I438": LOCATION = "R135" #&CDS_LOCATION = "R135" &SEC = "1" #&CDS_SEC = "1";
"1":   PN = "1"  !CDS_PN = "1";
"2":   PN = "2"  !CDS_PN = "2";
BODY = "RESISTOR","I439": LOCATION = "R137" #&CDS_LOCATION = "R137" &SEC = "1" #&CDS_SEC = "1";
"1":   PN = "1"  !CDS_PN = "1";
"2":   PN = "2"  !CDS_PN = "2";
BODY = "RESISTOR","I440": LOCATION = "R402" #&CDS_LOCATION = "R402" &SEC = "1" #&CDS_SEC = "1";
"1":   PN = "1"  !CDS_PN = "1";
"2":   PN = "2"  !CDS_PN = "2";
BODY = "DIODE_4_V1","I442": #LOCATION = "CR7" !CDS_LOCATION = "CR7" &SEC = "1" #&CDS_SEC = "1";
"GND":   PN = "1"  !CDS_PN = "1";
"IO1":   PN = "2"  !CDS_PN = "2";
"IO2":   PN = "3"  !CDS_PN = "3";
"VDD":   PN = "4"  !CDS_PN = "4";
BODY = "DIODE_4_V1","I443": #LOCATION = "CR6" !CDS_LOCATION = "CR6" &SEC = "1" #&CDS_SEC = "1";
"GND":   PN = "1"  !CDS_PN = "1";
"IO1":   PN = "2"  !CDS_PN = "2";
"IO2":   PN = "3"  !CDS_PN = "3";
"VDD":   PN = "4"  !CDS_PN = "4";
BODY = "RESISTOR","I446": LOCATION = "R133" #&CDS_LOCATION = "R133" &SEC = "1" #&CDS_SEC = "1";
"1":   PN = "1"  !CDS_PN = "1";
"2":   PN = "2"  !CDS_PN = "2";
BODY = "MT25QL128ABA1ESE_SOP8","I456": LOCATION = "U23" #&CDS_LOCATION = "U23" &SEC = "1" #&CDS_SEC = "1";
"C":   PN = "6"  !CDS_PN = "6";
"DQ0":   PN = "5"  !CDS_PN = "5";
"DQ1":   PN = "2"  !CDS_PN = "2";
"HOLD/DQ3*":   PN = "7"  !CDS_PN = "7";
"S*":   PN = "1"  !CDS_PN = "1";
"VCC":   PN = "8"  !CDS_PN = "8";
"VSS":   PN = "4"  !CDS_PN = "4";
"W/DQ2*":   PN = "3"  !CDS_PN = "3";
BODY = "RESISTOR","I462": LOCATION = "R199" #&CDS_LOCATION = "R199" &SEC = "1" #&CDS_SEC = "1";
"1":   PN = "1"  !CDS_PN = "1";
"2":   PN = "2"  !CDS_PN = "2";
BODY = "RESISTOR","I463": #LOCATION = "R201" !CDS_LOCATION = "R201" &SEC = "1" #&CDS_SEC = "1";
"1":   PN = "1"  !CDS_PN = "1";
"2":   PN = "2"  !CDS_PN = "2";
BODY = "RESISTOR","I464": #LOCATION = "R202" !CDS_LOCATION = "R202" &SEC = "1" #&CDS_SEC = "1";
"1":   PN = "1"  !CDS_PN = "1";
"2":   PN = "2"  !CDS_PN = "2";
BODY = "RESISTOR","I465": #LOCATION = "R200" !CDS_LOCATION = "R200" &SEC = "1" #&CDS_SEC = "1";
"1":   PN = "1"  !CDS_PN = "1";
"2":   PN = "2"  !CDS_PN = "2";
BODY = "RESISTOR","I466": #LOCATION = "R204" !CDS_LOCATION = "R204" &SEC = "1" #&CDS_SEC = "1";
"1":   PN = "1"  !CDS_PN = "1";
"2":   PN = "2"  !CDS_PN = "2";
BODY = "RESISTOR","I467": LOCATION = "R203" #&CDS_LOCATION = "R203" &SEC = "1" #&CDS_SEC = "1";
"1":   PN = "1"  !CDS_PN = "1";
"2":   PN = "2"  !CDS_PN = "2";
BODY = "RESISTOR","I468": #LOCATION = "R205" !CDS_LOCATION = "R205" &SEC = "1" #&CDS_SEC = "1";
"1":   PN = "1"  !CDS_PN = "1";
"2":   PN = "2"  !CDS_PN = "2";
BODY = "RESISTOR","I469": #LOCATION = "R206" !CDS_LOCATION = "R206" &SEC = "1" #&CDS_SEC = "1";
"1":   PN = "1"  !CDS_PN = "1";
"2":   PN = "2"  !CDS_PN = "2";
BODY = "RESISTOR","I470": LOCATION = "R192" #&CDS_LOCATION = "R192" &SEC = "1" #&CDS_SEC = "1";
"1":   PN = "1"  !CDS_PN = "1";
"2":   PN = "2"  !CDS_PN = "2";
BODY = "RESISTOR","I471": LOCATION = "R191" #&CDS_LOCATION = "R191" &SEC = "1" #&CDS_SEC = "1";
"1":   PN = "1"  !CDS_PN = "1";
"2":   PN = "2"  !CDS_PN = "2";
BODY = "CAPACITOR","I472": LOCATION = "C199" #&CDS_LOCATION = "C199" &SEC = "1" #&CDS_SEC = "1";
"1":   PN = "1"  !CDS_PN = "1";
"2":   PN = "2"  !CDS_PN = "2";
BODY = "CAPACITOR","I473": LOCATION = "C198" #&CDS_LOCATION = "C198" &SEC = "1" #&CDS_SEC = "1";
"1":   PN = "1"  !CDS_PN = "1";
"2":   PN = "2"  !CDS_PN = "2";
DRAWING = "@timecard_lib.timecard(sch_1):page12";
BODY = "DIODE_4_V1","I42": LOCATION = "CR5" #&CDS_LOCATION = "CR5" &SEC = "1" #&CDS_SEC = "1";
"GND":   PN = "1"  !CDS_PN = "1";
"IO1":   PN = "2"  !CDS_PN = "2";
"IO2":   PN = "3"  !CDS_PN = "3";
"VDD":   PN = "4"  !CDS_PN = "4";
BODY = "RESISTOR","I63": LOCATION = "R156" #&CDS_LOCATION = "R156" &SEC = "1" #&CDS_SEC = "1";
"1":   PN = "1"  !CDS_PN = "1";
"2":   PN = "2"  !CDS_PN = "2";
BODY = "RESISTOR","I88": LOCATION = "R365" #&CDS_LOCATION = "R365" &SEC = "1" #&CDS_SEC = "1";
"1":   PN = "1"  !CDS_PN = "1";
"2":   PN = "2"  !CDS_PN = "2";
BODY = "DIODE_4_V1","I179": #LOCATION = "CR4" !CDS_LOCATION = "CR4" &SEC = "1" #&CDS_SEC = "1";
"GND":   PN = "1"  !CDS_PN = "1";
"IO1":   PN = "2"  !CDS_PN = "2";
"IO2":   PN = "3"  !CDS_PN = "3";
"VDD":   PN = "4"  !CDS_PN = "4";
BODY = "RESISTOR","I197": #LOCATION = "R122" !CDS_LOCATION = "R122" &SEC = "1" #&CDS_SEC = "1";
"1":   PN = "1"  !CDS_PN = "1";
"2":   PN = "2"  !CDS_PN = "2";
BODY = "74HCT2G125DP_TSSOP8","I204": #LOCATION = "U13" !CDS_LOCATION = "U13" &SEC = "1" #&CDS_SEC = "1";
"1A":   PN = "2"  !CDS_PN = "2";
"1OE*":   PN = "1"  !CDS_PN = "1";
"1Y":   PN = "6"  !CDS_PN = "6";
"2A":   PN = "5"  !CDS_PN = "5";
"2OE*":   PN = "7"  !CDS_PN = "7";
"2Y":   PN = "3"  !CDS_PN = "3";
"GND":   PN = "4"  !CDS_PN = "4";
"VCC":   PN = "8"  !CDS_PN = "8";
BODY = "RESISTOR","I206": #LOCATION = "R377" !CDS_LOCATION = "R377" &SEC = "1" #&CDS_SEC = "1";
"1":   PN = "1"  !CDS_PN = "1";
"2":   PN = "2"  !CDS_PN = "2";
BODY = "CAPACITOR","I207": LOCATION = "C83" #&CDS_LOCATION = "C83" &SEC = "1" #&CDS_SEC = "1";
"1":   PN = "1"  !CDS_PN = "1";
"2":   PN = "2"  !CDS_PN = "2";
BODY = "RESISTOR","I209": LOCATION = "R367" #&CDS_LOCATION = "R367" &SEC = "1" #&CDS_SEC = "1";
"1":   PN = "1"  !CDS_PN = "1";
"2":   PN = "2"  !CDS_PN = "2";
BODY = "74HCT2G125DP_TSSOP8","I226": #LOCATION = "U14" !CDS_LOCATION = "U14" &SEC = "1" #&CDS_SEC = "1";
"1A":   PN = "2"  !CDS_PN = "2";
"1OE*":   PN = "1"  !CDS_PN = "1";
"1Y":   PN = "6"  !CDS_PN = "6";
"2A":   PN = "5"  !CDS_PN = "5";
"2OE*":   PN = "7"  !CDS_PN = "7";
"2Y":   PN = "3"  !CDS_PN = "3";
"GND":   PN = "4"  !CDS_PN = "4";
"VCC":   PN = "8"  !CDS_PN = "8";
BODY = "RESISTOR","I228": #LOCATION = "R123" !CDS_LOCATION = "R123" &SEC = "1" #&CDS_SEC = "1";
"1":   PN = "1"  !CDS_PN = "1";
"2":   PN = "2"  !CDS_PN = "2";
BODY = "RESISTOR","I229": #LOCATION = "R370" !CDS_LOCATION = "R370" &SEC = "1" #&CDS_SEC = "1";
"1":   PN = "1"  !CDS_PN = "1";
"2":   PN = "2"  !CDS_PN = "2";
BODY = "CAPACITOR","I231": #LOCATION = "C82" !CDS_LOCATION = "C82" &SEC = "1" #&CDS_SEC = "1";
"1":   PN = "1"  !CDS_PN = "1";
"2":   PN = "2"  !CDS_PN = "2";
BODY = "RESISTOR","I233": #LOCATION = "R368" !CDS_LOCATION = "R368" &SEC = "1" #&CDS_SEC = "1";
"1":   PN = "1"  !CDS_PN = "1";
"2":   PN = "2"  !CDS_PN = "2";
BODY = "RESISTOR","I234": #LOCATION = "R379" !CDS_LOCATION = "R379" &SEC = "1" #&CDS_SEC = "1";
"1":   PN = "1"  !CDS_PN = "1";
"2":   PN = "2"  !CDS_PN = "2";
BODY = "RESISTOR","I237": #LOCATION = "R157" !CDS_LOCATION = "R157" &SEC = "1" #&CDS_SEC = "1";
"1":   PN = "1"  !CDS_PN = "1";
"2":   PN = "2"  !CDS_PN = "2";
BODY = "74HCT2G125DP_TSSOP8","I255": #LOCATION = "U15" !CDS_LOCATION = "U15" &SEC = "1" #&CDS_SEC = "1";
"1A":   PN = "2"  !CDS_PN = "2";
"1OE*":   PN = "1"  !CDS_PN = "1";
"1Y":   PN = "6"  !CDS_PN = "6";
"2A":   PN = "5"  !CDS_PN = "5";
"2OE*":   PN = "7"  !CDS_PN = "7";
"2Y":   PN = "3"  !CDS_PN = "3";
"GND":   PN = "4"  !CDS_PN = "4";
"VCC":   PN = "8"  !CDS_PN = "8";
BODY = "RESISTOR","I257": #LOCATION = "R127" !CDS_LOCATION = "R127" &SEC = "1" #&CDS_SEC = "1";
"1":   PN = "1"  !CDS_PN = "1";
"2":   PN = "2"  !CDS_PN = "2";
BODY = "RESISTOR","I258": #LOCATION = "R371" !CDS_LOCATION = "R371" &SEC = "1" #&CDS_SEC = "1";
"1":   PN = "1"  !CDS_PN = "1";
"2":   PN = "2"  !CDS_PN = "2";
BODY = "RESISTOR","I261": #LOCATION = "R361" !CDS_LOCATION = "R361" &SEC = "1" #&CDS_SEC = "1";
"1":   PN = "1"  !CDS_PN = "1";
"2":   PN = "2"  !CDS_PN = "2";
BODY = "RESISTOR","I262": #LOCATION = "R381" !CDS_LOCATION = "R381" &SEC = "1" #&CDS_SEC = "1";
"1":   PN = "1"  !CDS_PN = "1";
"2":   PN = "2"  !CDS_PN = "2";
BODY = "RESISTOR","I265": #LOCATION = "R120" !CDS_LOCATION = "R120" &SEC = "1" #&CDS_SEC = "1";
"1":   PN = "1"  !CDS_PN = "1";
"2":   PN = "2"  !CDS_PN = "2";
BODY = "CAPACITOR","I272": LOCATION = "C85" #&CDS_LOCATION = "C85" &SEC = "1" #&CDS_SEC = "1";
"1":   PN = "1"  !CDS_PN = "1";
"2":   PN = "2"  !CDS_PN = "2";
BODY = "74HCT2G125DP_TSSOP8","I273": #LOCATION = "U16" !CDS_LOCATION = "U16" &SEC = "1" #&CDS_SEC = "1";
"1A":   PN = "2"  !CDS_PN = "2";
"1OE*":   PN = "1"  !CDS_PN = "1";
"1Y":   PN = "6"  !CDS_PN = "6";
"2A":   PN = "5"  !CDS_PN = "5";
"2OE*":   PN = "7"  !CDS_PN = "7";
"2Y":   PN = "3"  !CDS_PN = "3";
"GND":   PN = "4"  !CDS_PN = "4";
"VCC":   PN = "8"  !CDS_PN = "8";
BODY = "RESISTOR","I275": #LOCATION = "R372" !CDS_LOCATION = "R372" &SEC = "1" #&CDS_SEC = "1";
"1":   PN = "1"  !CDS_PN = "1";
"2":   PN = "2"  !CDS_PN = "2";
BODY = "RESISTOR","I276": #LOCATION = "R126" !CDS_LOCATION = "R126" &SEC = "1" #&CDS_SEC = "1";
"1":   PN = "1"  !CDS_PN = "1";
"2":   PN = "2"  !CDS_PN = "2";
BODY = "RESISTOR","I280": #LOCATION = "R331" !CDS_LOCATION = "R331" &SEC = "1" #&CDS_SEC = "1";
"1":   PN = "1"  !CDS_PN = "1";
"2":   PN = "2"  !CDS_PN = "2";
BODY = "RESISTOR","I281": #LOCATION = "R383" !CDS_LOCATION = "R383" &SEC = "1" #&CDS_SEC = "1";
"1":   PN = "1"  !CDS_PN = "1";
"2":   PN = "2"  !CDS_PN = "2";
BODY = "RESISTOR","I284": #LOCATION = "R121" !CDS_LOCATION = "R121" &SEC = "1" #&CDS_SEC = "1";
"1":   PN = "1"  !CDS_PN = "1";
"2":   PN = "2"  !CDS_PN = "2";
BODY = "CAPACITOR","I289": LOCATION = "C84" #&CDS_LOCATION = "C84" &SEC = "1" #&CDS_SEC = "1";
"1":   PN = "1"  !CDS_PN = "1";
"2":   PN = "2"  !CDS_PN = "2";
BODY = "CONN_JACK_1P_GH4_S_TH","I290": #LOCATION = "J1" !CDS_LOCATION = "J1" &SEC = "1" #&CDS_SEC = "1";
"1":   PN = "1"  !CDS_PN = "1";
"GH1":   PN = "GH1"  !CDS_PN = "GH1";
"GH2":   PN = "GH2"  !CDS_PN = "GH2";
"GH3":   PN = "GH3"  !CDS_PN = "GH3";
"GH4":   PN = "GH4"  !CDS_PN = "GH4";
BODY = "CONN_JACK_1P_GH4_S_TH","I294": #LOCATION = "J2" !CDS_LOCATION = "J2" &SEC = "1" #&CDS_SEC = "1";
"1":   PN = "1"  !CDS_PN = "1";
"GH1":   PN = "GH1"  !CDS_PN = "GH1";
"GH2":   PN = "GH2"  !CDS_PN = "GH2";
"GH3":   PN = "GH3"  !CDS_PN = "GH3";
"GH4":   PN = "GH4"  !CDS_PN = "GH4";
BODY = "CONN_JACK_1P_GH4_S_TH","I297": #LOCATION = "J3" !CDS_LOCATION = "J3" &SEC = "1" #&CDS_SEC = "1";
"1":   PN = "1"  !CDS_PN = "1";
"GH1":   PN = "GH1"  !CDS_PN = "GH1";
"GH2":   PN = "GH2"  !CDS_PN = "GH2";
"GH3":   PN = "GH3"  !CDS_PN = "GH3";
"GH4":   PN = "GH4"  !CDS_PN = "GH4";
BODY = "CONN_JACK_1P_GH4_S_TH","I300": #LOCATION = "J4" !CDS_LOCATION = "J4" &SEC = "1" #&CDS_SEC = "1";
"1":   PN = "1"  !CDS_PN = "1";
"GH1":   PN = "GH1"  !CDS_PN = "GH1";
"GH2":   PN = "GH2"  !CDS_PN = "GH2";
"GH3":   PN = "GH3"  !CDS_PN = "GH3";
"GH4":   PN = "GH4"  !CDS_PN = "GH4";
BODY = "CAPACITOR","I318": LOCATION = "C310" #&CDS_LOCATION = "C310" &SEC = "1" #&CDS_SEC = "1";
"1":   PN = "1"  !CDS_PN = "1";
"2":   PN = "2"  !CDS_PN = "2";
BODY = "RESISTOR","I319": LOCATION = "R492" #&CDS_LOCATION = "R492" &SEC = "1" #&CDS_SEC = "1";
"1":   PN = "1"  !CDS_PN = "1";
"2":   PN = "2"  !CDS_PN = "2";
BODY = "RESISTOR","I320": LOCATION = "R496" #&CDS_LOCATION = "R496" &SEC = "1" #&CDS_SEC = "1";
"1":   PN = "1"  !CDS_PN = "1";
"2":   PN = "2"  !CDS_PN = "2";
BODY = "RESISTOR","I322": LOCATION = "R497" #&CDS_LOCATION = "R497" &SEC = "1" #&CDS_SEC = "1";
"1":   PN = "1"  !CDS_PN = "1";
"2":   PN = "2"  !CDS_PN = "2";
BODY = "RESISTOR","I323": LOCATION = "R493" #&CDS_LOCATION = "R493" &SEC = "1" #&CDS_SEC = "1";
"1":   PN = "1"  !CDS_PN = "1";
"2":   PN = "2"  !CDS_PN = "2";
BODY = "RESISTOR","I326": LOCATION = "R494" #&CDS_LOCATION = "R494" &SEC = "1" #&CDS_SEC = "1";
"1":   PN = "1"  !CDS_PN = "1";
"2":   PN = "2"  !CDS_PN = "2";
BODY = "RESISTOR","I327": LOCATION = "R498" #&CDS_LOCATION = "R498" &SEC = "1" #&CDS_SEC = "1";
"1":   PN = "1"  !CDS_PN = "1";
"2":   PN = "2"  !CDS_PN = "2";
BODY = "CAPACITOR","I328": LOCATION = "C317" #&CDS_LOCATION = "C317" &SEC = "1" #&CDS_SEC = "1";
"1":   PN = "1"  !CDS_PN = "1";
"2":   PN = "2"  !CDS_PN = "2";
BODY = "CAPACITOR","I321": LOCATION = "C311" #&CDS_LOCATION = "C311" &SEC = "1" #&CDS_SEC = "1";
"1":   PN = "1"  !CDS_PN = "1";
"2":   PN = "2"  !CDS_PN = "2";
BODY = "RESISTOR","I330": LOCATION = "R495" #&CDS_LOCATION = "R495" &SEC = "1" #&CDS_SEC = "1";
"1":   PN = "1"  !CDS_PN = "1";
"2":   PN = "2"  !CDS_PN = "2";
BODY = "RESISTOR","I331": LOCATION = "R499" #&CDS_LOCATION = "R499" &SEC = "1" #&CDS_SEC = "1";
"1":   PN = "1"  !CDS_PN = "1";
"2":   PN = "2"  !CDS_PN = "2";
BODY = "CAPACITOR","I332": LOCATION = "C318" #&CDS_LOCATION = "C318" &SEC = "1" #&CDS_SEC = "1";
"1":   PN = "1"  !CDS_PN = "1";
"2":   PN = "2"  !CDS_PN = "2";
DRAWING = "@timecard_lib.timecard(sch_1):page524";
BODY = "CL1001485A","I3": LOCATION = "U17" #&CDS_LOCATION = "U17" &SEC = "1" #&CDS_SEC = "1";
"1":   PN = "1"  !CDS_PN = "1";
"2":   PN = "2"  !CDS_PN = "2";
"3":   PN = "3"  !CDS_PN = "3";
"4":   PN = "4"  !CDS_PN = "4";
"5":   PN = "5"  !CDS_PN = "5";
"6":   PN = "6"  !CDS_PN = "6";
BODY = "CAPACITOR","I7": LOCATION = "C86" #&CDS_LOCATION = "C86" &SEC = "1" #&CDS_SEC = "1";
"1":   PN = "1"  !CDS_PN = "1";
"2":   PN = "2"  !CDS_PN = "2";
BODY = "XTAL_4","I8": LOCATION = "Y2" #&CDS_LOCATION = "Y2" &SEC = "1" #&CDS_SEC = "1";
"1":   PN = "1"  !CDS_PN = "1";
"2":   PN = "2"  !CDS_PN = "2";
"3":   PN = "3"  !CDS_PN = "3";
"4":   PN = "4"  !CDS_PN = "4";
BODY = "CAPACITOR","I10": LOCATION = "C87" #&CDS_LOCATION = "C87" &SEC = "1" #&CDS_SEC = "1";
"1":   PN = "1"  !CDS_PN = "1";
"2":   PN = "2"  !CDS_PN = "2";
BODY = "RESISTOR","I23": LOCATION = "R130" #&CDS_LOCATION = "R130" &SEC = "1" #&CDS_SEC = "1";
"1":   PN = "1"  !CDS_PN = "1";
"2":   PN = "2"  !CDS_PN = "2";
BODY = "RESISTOR","I26": LOCATION = "R129" #&CDS_LOCATION = "R129" &SEC = "1" #&CDS_SEC = "1";
"1":   PN = "1"  !CDS_PN = "1";
"2":   PN = "2"  !CDS_PN = "2";
BODY = "RESISTOR","I27": LOCATION = "R18" #&CDS_LOCATION = "R18" &SEC = "1" #&CDS_SEC = "1";
"1":   PN = "1"  !CDS_PN = "1";
"2":   PN = "2"  !CDS_PN = "2";
BODY = "RESISTOR","I28": LOCATION = "R128" #&CDS_LOCATION = "R128" &SEC = "1" #&CDS_SEC = "1";
"1":   PN = "1"  !CDS_PN = "1";
"2":   PN = "2"  !CDS_PN = "2";
BODY = "FT4232HL_REEL_QFP64","I64": LOCATION = "U18" #&CDS_LOCATION = "U18" &SEC = "1" #&CDS_SEC = "1";
"ADBUS0":   PN = "16"  !CDS_PN = "16";
"ADBUS1":   PN = "17"  !CDS_PN = "17";
"ADBUS2":   PN = "18"  !CDS_PN = "18";
"ADBUS3":   PN = "19"  !CDS_PN = "19";
"ADBUS4":   PN = "21"  !CDS_PN = "21";
"ADBUS5":   PN = "22"  !CDS_PN = "22";
"ADBUS6":   PN = "23"  !CDS_PN = "23";
"ADBUS7":   PN = "24"  !CDS_PN = "24";
"AGND":   PN = "10"  !CDS_PN = "10";
"BDBUS0":   PN = "26"  !CDS_PN = "26";
"BDBUS1":   PN = "27"  !CDS_PN = "27";
"BDBUS2":   PN = "28"  !CDS_PN = "28";
"BDBUS3":   PN = "29"  !CDS_PN = "29";
"BDBUS4":   PN = "30"  !CDS_PN = "30";
"BDBUS5":   PN = "32"  !CDS_PN = "32";
"BDBUS6":   PN = "33"  !CDS_PN = "33";
"BDBUS7":   PN = "34"  !CDS_PN = "34";
"CDBUS0":   PN = "38"  !CDS_PN = "38";
"CDBUS1":   PN = "39"  !CDS_PN = "39";
"CDBUS2":   PN = "40"  !CDS_PN = "40";
"CDBUS3":   PN = "41"  !CDS_PN = "41";
"CDBUS4":   PN = "43"  !CDS_PN = "43";
"CDBUS5":   PN = "44"  !CDS_PN = "44";
"CDBUS6":   PN = "45"  !CDS_PN = "45";
"CDBUS7":   PN = "46"  !CDS_PN = "46";
"DDBUS0":   PN = "48"  !CDS_PN = "48";
"DDBUS1":   PN = "52"  !CDS_PN = "52";
"DDBUS2":   PN = "53"  !CDS_PN = "53";
"DDBUS3":   PN = "54"  !CDS_PN = "54";
"DDBUS4":   PN = "55"  !CDS_PN = "55";
"DDBUS5":   PN = "57"  !CDS_PN = "57";
"DDBUS6":   PN = "58"  !CDS_PN = "58";
"DDBUS7":   PN = "59"  !CDS_PN = "59";
"DM":   PN = "7"  !CDS_PN = "7";
"DP":   PN = "8"  !CDS_PN = "8";
"EECLK":   PN = "62"  !CDS_PN = "62";
"EECS":   PN = "63"  !CDS_PN = "63";
"EEDATA":   PN = "61"  !CDS_PN = "61";
"GND_1":   PN = "51"  !CDS_PN = "51";
"GND_2":   PN = "47"  !CDS_PN = "47";
"GND_3":   PN = "35"  !CDS_PN = "35";
"GND_4":   PN = "25"  !CDS_PN = "25";
"GND_5":   PN = "15"  !CDS_PN = "15";
"GND_6":   PN = "11"  !CDS_PN = "11";
"GND_7":   PN = "5"  !CDS_PN = "5";
"GND_8":   PN = "1"  !CDS_PN = "1";
"OSCI":   PN = "2"  !CDS_PN = "2";
"OSCO":   PN = "3"  !CDS_PN = "3";
"PWREN*":   PN = "60"  !CDS_PN = "60";
"REF":   PN = "6"  !CDS_PN = "6";
"RESET*":   PN = "14"  !CDS_PN = "14";
"SUSPEND*":   PN = "36"  !CDS_PN = "36";
"TEST":   PN = "13"  !CDS_PN = "13";
"VCCIO_1":   PN = "56"  !CDS_PN = "56";
"VCCIO_2":   PN = "42"  !CDS_PN = "42";
"VCCIO_3":   PN = "31"  !CDS_PN = "31";
"VCCIO_4":   PN = "20"  !CDS_PN = "20";
"VCORE_1":   PN = "64"  !CDS_PN = "64";
"VCORE_2":   PN = "37"  !CDS_PN = "37";
"VCORE_3":   PN = "12"  !CDS_PN = "12";
"VPHY":   PN = "4"  !CDS_PN = "4";
"VPLL":   PN = "9"  !CDS_PN = "9";
"VREGIN":   PN = "50"  !CDS_PN = "50";
"VREGOUT":   PN = "49"  !CDS_PN = "49";
BODY = "RESISTOR","I106": LOCATION = "R463" #&CDS_LOCATION = "R463" &SEC = "1" #&CDS_SEC = "1";
"1":   PN = "1"  !CDS_PN = "1";
"2":   PN = "2"  !CDS_PN = "2";
BODY = "FERRITEBEAD","I118": LOCATION = "L22" #&CDS_LOCATION = "L22" &SEC = "1" #&CDS_SEC = "1";
"1":   PN = "1"  !CDS_PN = "1";
"2":   PN = "2"  !CDS_PN = "2";
BODY = "RESISTOR","I121": LOCATION = "R460" #&CDS_LOCATION = "R460" &SEC = "1" #&CDS_SEC = "1";
"1":   PN = "1"  !CDS_PN = "1";
"2":   PN = "2"  !CDS_PN = "2";
BODY = "CAPACITOR","I123": LOCATION = "C90" #&CDS_LOCATION = "C90" &SEC = "1" #&CDS_SEC = "1";
"1":   PN = "1"  !CDS_PN = "1";
"2":   PN = "2"  !CDS_PN = "2";
BODY = "FERRITEBEAD","I127": LOCATION = "L4" #&CDS_LOCATION = "L4" &SEC = "1" #&CDS_SEC = "1";
"1":   PN = "1"  !CDS_PN = "1";
"2":   PN = "2"  !CDS_PN = "2";
BODY = "CAPACITOR","I128": LOCATION = "C91" #&CDS_LOCATION = "C91" &SEC = "1" #&CDS_SEC = "1";
"1":   PN = "1"  !CDS_PN = "1";
"2":   PN = "2"  !CDS_PN = "2";
BODY = "RESISTOR","I139": LOCATION = "R470" #&CDS_LOCATION = "R470" &SEC = "1" #&CDS_SEC = "1";
"1":   PN = "1"  !CDS_PN = "1";
"2":   PN = "2"  !CDS_PN = "2";
BODY = "RESISTOR","I140": LOCATION = "R468" #&CDS_LOCATION = "R468" &SEC = "1" #&CDS_SEC = "1";
"1":   PN = "1"  !CDS_PN = "1";
"2":   PN = "2"  !CDS_PN = "2";
BODY = "RESISTOR","I141": LOCATION = "R467" #&CDS_LOCATION = "R467" &SEC = "1" #&CDS_SEC = "1";
"1":   PN = "1"  !CDS_PN = "1";
"2":   PN = "2"  !CDS_PN = "2";
BODY = "RESISTOR","I142": LOCATION = "R469" #&CDS_LOCATION = "R469" &SEC = "1" #&CDS_SEC = "1";
"1":   PN = "1"  !CDS_PN = "1";
"2":   PN = "2"  !CDS_PN = "2";
BODY = "RESISTOR","I149": LOCATION = "R480" #&CDS_LOCATION = "R480" &SEC = "1" #&CDS_SEC = "1";
"1":   PN = "1"  !CDS_PN = "1";
"2":   PN = "2"  !CDS_PN = "2";
BODY = "RESISTOR","I150": LOCATION = "R481" #&CDS_LOCATION = "R481" &SEC = "1" #&CDS_SEC = "1";
"1":   PN = "1"  !CDS_PN = "1";
"2":   PN = "2"  !CDS_PN = "2";
BODY = "RESISTOR","I153": LOCATION = "R353" #&CDS_LOCATION = "R353" &SEC = "1" #&CDS_SEC = "1";
"1":   PN = "1"  !CDS_PN = "1";
"2":   PN = "2"  !CDS_PN = "2";
BODY = "RESISTOR","I154": LOCATION = "R352" #&CDS_LOCATION = "R352" &SEC = "1" #&CDS_SEC = "1";
"1":   PN = "1"  !CDS_PN = "1";
"2":   PN = "2"  !CDS_PN = "2";
BODY = "RESISTOR","I166": LOCATION = "R472" #&CDS_LOCATION = "R472" &SEC = "1" #&CDS_SEC = "1";
"1":   PN = "1"  !CDS_PN = "1";
"2":   PN = "2"  !CDS_PN = "2";
BODY = "RESISTOR","I169": LOCATION = "R471" #&CDS_LOCATION = "R471" &SEC = "1" #&CDS_SEC = "1";
"1":   PN = "1"  !CDS_PN = "1";
"2":   PN = "2"  !CDS_PN = "2";
BODY = "RESISTOR","I170": LOCATION = "R473" #&CDS_LOCATION = "R473" &SEC = "1" #&CDS_SEC = "1";
"1":   PN = "1"  !CDS_PN = "1";
"2":   PN = "2"  !CDS_PN = "2";
BODY = "G200_10283_01","I173": LOCATION = "J10" #&CDS_LOCATION = "J10" &SEC = "1" #&CDS_SEC = "1";
"1":   PN = "1"  !CDS_PN = "1";
"2":   PN = "2"  !CDS_PN = "2";
"3":   PN = "3"  !CDS_PN = "3";
"4":   PN = "4"  !CDS_PN = "4";
"5":   PN = "5"  !CDS_PN = "5";
"6":   PN = "6"  !CDS_PN = "6";
"7":   PN = "7"  !CDS_PN = "7";
"8":   PN = "8"  !CDS_PN = "8";
"9":   PN = "9"  !CDS_PN = "9";
"10":   PN = "10"  !CDS_PN = "10";
BODY = "RESISTOR","I184": LOCATION = "R349" #&CDS_LOCATION = "R349" &SEC = "1" #&CDS_SEC = "1";
"1":   PN = "1"  !CDS_PN = "1";
"2":   PN = "2"  !CDS_PN = "2";
BODY = "RESISTOR","I187": LOCATION = "R131" #&CDS_LOCATION = "R131" &SEC = "1" #&CDS_SEC = "1";
"1":   PN = "1"  !CDS_PN = "1";
"2":   PN = "2"  !CDS_PN = "2";
BODY = "RESISTOR","I188": LOCATION = "R132" #&CDS_LOCATION = "R132" &SEC = "1" #&CDS_SEC = "1";
"1":   PN = "1"  !CDS_PN = "1";
"2":   PN = "2"  !CDS_PN = "2";
BODY = "RESISTOR","I190": LOCATION = "R478" #&CDS_LOCATION = "R478" &SEC = "1" #&CDS_SEC = "1";
"1":   PN = "1"  !CDS_PN = "1";
"2":   PN = "2"  !CDS_PN = "2";
BODY = "RESISTOR","I191": LOCATION = "R479" #&CDS_LOCATION = "R479" &SEC = "1" #&CDS_SEC = "1";
"1":   PN = "1"  !CDS_PN = "1";
"2":   PN = "2"  !CDS_PN = "2";
BODY = "RESISTOR","I198": LOCATION = "R466" #&CDS_LOCATION = "R466" &SEC = "1" #&CDS_SEC = "1";
"1":   PN = "1"  !CDS_PN = "1";
"2":   PN = "2"  !CDS_PN = "2";
BODY = "CAT93C46VI_GT3_SOIC8","I200": LOCATION = "U31" #&CDS_LOCATION = "U31" &SEC = "1" #&CDS_SEC = "1";
"CS":   PN = "1"  !CDS_PN = "1";
"DI":   PN = "3"  !CDS_PN = "3";
"DO":   PN = "4"  !CDS_PN = "4";
"NC":   PN = "7"  !CDS_PN = "7";
"ORG":   PN = "6"  !CDS_PN = "6";
"SK":   PN = "2"  !CDS_PN = "2";
BODY = "CAT93C46VI_GT3_SOIC8","I201": LOCATION = "U31" #&CDS_LOCATION = "U31" &SEC = "2" #&CDS_SEC = "2";
"GND":   PN = "5"  !CDS_PN = "5";
"VCC":   PN = "8"  !CDS_PN = "8";
BODY = "RESISTOR","I206": LOCATION = "R447" #&CDS_LOCATION = "R447" &SEC = "1" #&CDS_SEC = "1";
"1":   PN = "1"  !CDS_PN = "1";
"2":   PN = "2"  !CDS_PN = "2";
BODY = "RESISTOR","I207": LOCATION = "R446" #&CDS_LOCATION = "R446" &SEC = "1" #&CDS_SEC = "1";
"1":   PN = "1"  !CDS_PN = "1";
"2":   PN = "2"  !CDS_PN = "2";
BODY = "RESISTOR","I208": LOCATION = "R444" #&CDS_LOCATION = "R444" &SEC = "1" #&CDS_SEC = "1";
"1":   PN = "1"  !CDS_PN = "1";
"2":   PN = "2"  !CDS_PN = "2";
BODY = "RESISTOR","I287": LOCATION = "R455" #&CDS_LOCATION = "R455" &SEC = "1" #&CDS_SEC = "1";
"1":   PN = "1"  !CDS_PN = "1";
"2":   PN = "2"  !CDS_PN = "2";
BODY = "RESISTOR","I310": LOCATION = "R454" #&CDS_LOCATION = "R454" &SEC = "1" #&CDS_SEC = "1";
"1":   PN = "1"  !CDS_PN = "1";
"2":   PN = "2"  !CDS_PN = "2";
BODY = "TP_PIONT","I311": LOCATION = "TP5" #&CDS_LOCATION = "TP5" &SEC = "1" #&CDS_SEC = "1";
"1":   PN = "1"  !CDS_PN = "1";
BODY = "TP_PIONT","I312": LOCATION = "TP6" #&CDS_LOCATION = "TP6" &SEC = "1" #&CDS_SEC = "1";
"1":   PN = "1"  !CDS_PN = "1";
BODY = "TP_PIONT","I313": LOCATION = "TP7" #&CDS_LOCATION = "TP7" &SEC = "1" #&CDS_SEC = "1";
"1":   PN = "1"  !CDS_PN = "1";
BODY = "TP_PIONT","I314": LOCATION = "TP9" #&CDS_LOCATION = "TP9" &SEC = "1" #&CDS_SEC = "1";
"1":   PN = "1"  !CDS_PN = "1";
BODY = "TP_PIONT","I315": LOCATION = "TP8" #&CDS_LOCATION = "TP8" &SEC = "1" #&CDS_SEC = "1";
"1":   PN = "1"  !CDS_PN = "1";
BODY = "TP_PIONT","I316": LOCATION = "TP10" #&CDS_LOCATION = "TP10" &SEC = "1" #&CDS_SEC = "1";
"1":   PN = "1"  !CDS_PN = "1";
BODY = "RESISTOR","I368": LOCATION = "R456" #&CDS_LOCATION = "R456" &SEC = "1" #&CDS_SEC = "1";
"1":   PN = "1"  !CDS_PN = "1";
"2":   PN = "2"  !CDS_PN = "2";
BODY = "CAPACITOR","I373": LOCATION = "C101" #&CDS_LOCATION = "C101" &SEC = "1" #&CDS_SEC = "1";
"1":   PN = "1"  !CDS_PN = "1";
"2":   PN = "2"  !CDS_PN = "2";
BODY = "CAPACITOR","I374": LOCATION = "C100" #&CDS_LOCATION = "C100" &SEC = "1" #&CDS_SEC = "1";
"1":   PN = "1"  !CDS_PN = "1";
"2":   PN = "2"  !CDS_PN = "2";
BODY = "CAPACITOR","I375": LOCATION = "C95" #&CDS_LOCATION = "C95" &SEC = "1" #&CDS_SEC = "1";
"1":   PN = "1"  !CDS_PN = "1";
"2":   PN = "2"  !CDS_PN = "2";
BODY = "CAPACITOR","I376": LOCATION = "C96" #&CDS_LOCATION = "C96" &SEC = "1" #&CDS_SEC = "1";
"1":   PN = "1"  !CDS_PN = "1";
"2":   PN = "2"  !CDS_PN = "2";
BODY = "CAPACITOR","I377": LOCATION = "C94" #&CDS_LOCATION = "C94" &SEC = "1" #&CDS_SEC = "1";
"1":   PN = "1"  !CDS_PN = "1";
"2":   PN = "2"  !CDS_PN = "2";
BODY = "CAPACITOR","I378": LOCATION = "C88" #&CDS_LOCATION = "C88" &SEC = "1" #&CDS_SEC = "1";
"1":   PN = "1"  !CDS_PN = "1";
"2":   PN = "2"  !CDS_PN = "2";
BODY = "CAPACITOR","I379": LOCATION = "C98" #&CDS_LOCATION = "C98" &SEC = "1" #&CDS_SEC = "1";
"1":   PN = "1"  !CDS_PN = "1";
"2":   PN = "2"  !CDS_PN = "2";
BODY = "CAPACITOR","I380": LOCATION = "C99" #&CDS_LOCATION = "C99" &SEC = "1" #&CDS_SEC = "1";
"1":   PN = "1"  !CDS_PN = "1";
"2":   PN = "2"  !CDS_PN = "2";
BODY = "RESISTOR","I395": LOCATION = "R445" #&CDS_LOCATION = "R445" &SEC = "1" #&CDS_SEC = "1";
"1":   PN = "1"  !CDS_PN = "1";
"2":   PN = "2"  !CDS_PN = "2";
BODY = "TS3A5018PWR_TSSOP16","I400": LOCATION = "U38" #&CDS_LOCATION = "U38" &SEC = "1" #&CDS_SEC = "1";
"COM1":   PN = "4"  !CDS_PN = "4";
"COM2":   PN = "7"  !CDS_PN = "7";
"COM3":   PN = "9"  !CDS_PN = "9";
"COM4":   PN = "12"  !CDS_PN = "12";
"EN*":   PN = "15"  !CDS_PN = "15";
"IN":   PN = "1"  !CDS_PN = "1";
"NC1":   PN = "2"  !CDS_PN = "2";
"NC2":   PN = "5"  !CDS_PN = "5";
"NC3":   PN = "11"  !CDS_PN = "11";
"NC4":   PN = "14"  !CDS_PN = "14";
"NO1":   PN = "3"  !CDS_PN = "3";
"NO2":   PN = "6"  !CDS_PN = "6";
"NO3":   PN = "10"  !CDS_PN = "10";
"NO4":   PN = "13"  !CDS_PN = "13";
BODY = "NLASB3157DFT2G_SC88","I407": LOCATION = "U39" #&CDS_LOCATION = "U39" &SEC = "1" #&CDS_SEC = "1";
"A":   PN = "4"  !CDS_PN = "4";
"B0":   PN = "3"  !CDS_PN = "3";
"B1":   PN = "1"  !CDS_PN = "1";
"SELECT":   PN = "6"  !CDS_PN = "6";
BODY = "NLASB3157DFT2G_SC88","I408": LOCATION = "U40" #&CDS_LOCATION = "U40" &SEC = "1" #&CDS_SEC = "1";
"A":   PN = "4"  !CDS_PN = "4";
"B0":   PN = "3"  !CDS_PN = "3";
"B1":   PN = "1"  !CDS_PN = "1";
"SELECT":   PN = "6"  !CDS_PN = "6";
BODY = "RESISTOR","I411": LOCATION = "R461" #&CDS_LOCATION = "R461" &SEC = "1" #&CDS_SEC = "1";
"1":   PN = "1"  !CDS_PN = "1";
"2":   PN = "2"  !CDS_PN = "2";
BODY = "RESISTOR","I412": LOCATION = "R462" #&CDS_LOCATION = "R462" &SEC = "1" #&CDS_SEC = "1";
"1":   PN = "1"  !CDS_PN = "1";
"2":   PN = "2"  !CDS_PN = "2";
BODY = "RESISTOR","I423": LOCATION = "R448" #&CDS_LOCATION = "R448" &SEC = "1" #&CDS_SEC = "1";
"1":   PN = "1"  !CDS_PN = "1";
"2":   PN = "2"  !CDS_PN = "2";
BODY = "RESISTOR","I424": LOCATION = "R449" #&CDS_LOCATION = "R449" &SEC = "1" #&CDS_SEC = "1";
"1":   PN = "1"  !CDS_PN = "1";
"2":   PN = "2"  !CDS_PN = "2";
BODY = "TS3A5018PWR_TSSOP16","I425": LOCATION = "U30" #&CDS_LOCATION = "U30" &SEC = "1" #&CDS_SEC = "1";
"COM1":   PN = "4"  !CDS_PN = "4";
"COM2":   PN = "7"  !CDS_PN = "7";
"COM3":   PN = "9"  !CDS_PN = "9";
"COM4":   PN = "12"  !CDS_PN = "12";
"EN*":   PN = "15"  !CDS_PN = "15";
"IN":   PN = "1"  !CDS_PN = "1";
"NC1":   PN = "2"  !CDS_PN = "2";
"NC2":   PN = "5"  !CDS_PN = "5";
"NC3":   PN = "11"  !CDS_PN = "11";
"NC4":   PN = "14"  !CDS_PN = "14";
"NO1":   PN = "3"  !CDS_PN = "3";
"NO2":   PN = "6"  !CDS_PN = "6";
"NO3":   PN = "10"  !CDS_PN = "10";
"NO4":   PN = "13"  !CDS_PN = "13";
BODY = "RESISTOR","I430": LOCATION = "R458" #&CDS_LOCATION = "R458" &SEC = "1" #&CDS_SEC = "1";
"1":   PN = "1"  !CDS_PN = "1";
"2":   PN = "2"  !CDS_PN = "2";
BODY = "RESISTOR","I431": LOCATION = "R457" #&CDS_LOCATION = "R457" &SEC = "1" #&CDS_SEC = "1";
"1":   PN = "1"  !CDS_PN = "1";
"2":   PN = "2"  !CDS_PN = "2";
BODY = "RESISTOR","I432": LOCATION = "R459" #&CDS_LOCATION = "R459" &SEC = "1" #&CDS_SEC = "1";
"1":   PN = "1"  !CDS_PN = "1";
"2":   PN = "2"  !CDS_PN = "2";
BODY = "RESISTOR","I440": LOCATION = "R450" #&CDS_LOCATION = "R450" &SEC = "1" #&CDS_SEC = "1";
"1":   PN = "1"  !CDS_PN = "1";
"2":   PN = "2"  !CDS_PN = "2";
BODY = "RESISTOR","I441": LOCATION = "R451" #&CDS_LOCATION = "R451" &SEC = "1" #&CDS_SEC = "1";
"1":   PN = "1"  !CDS_PN = "1";
"2":   PN = "2"  !CDS_PN = "2";
BODY = "RESISTOR","I442": LOCATION = "R453" #&CDS_LOCATION = "R453" &SEC = "1" #&CDS_SEC = "1";
"1":   PN = "1"  !CDS_PN = "1";
"2":   PN = "2"  !CDS_PN = "2";
BODY = "RESISTOR","I443": LOCATION = "R452" #&CDS_LOCATION = "R452" &SEC = "1" #&CDS_SEC = "1";
"1":   PN = "1"  !CDS_PN = "1";
"2":   PN = "2"  !CDS_PN = "2";
BODY = "POWERMOS_3P_NCH_V1","I445": LOCATION = "Q1" #&CDS_LOCATION = "Q1" &SEC = "1" #&CDS_SEC = "1";
"D":   PN = "3"  !CDS_PN = "3";
"G":   PN = "1"  !CDS_PN = "1";
"S":   PN = "2"  !CDS_PN = "2";
BODY = "RESISTOR","I446": LOCATION = "R443" #&CDS_LOCATION = "R443" &SEC = "1" #&CDS_SEC = "1";
"1":   PN = "1"  !CDS_PN = "1";
"2":   PN = "2"  !CDS_PN = "2";
BODY = "TS3A5018PWR_TSSOP16","I448": LOCATION = "U37" #&CDS_LOCATION = "U37" &SEC = "1" #&CDS_SEC = "1";
"COM1":   PN = "4"  !CDS_PN = "4";
"COM2":   PN = "7"  !CDS_PN = "7";
"COM3":   PN = "9"  !CDS_PN = "9";
"COM4":   PN = "12"  !CDS_PN = "12";
"EN*":   PN = "15"  !CDS_PN = "15";
"IN":   PN = "1"  !CDS_PN = "1";
"NC1":   PN = "2"  !CDS_PN = "2";
"NC2":   PN = "5"  !CDS_PN = "5";
"NC3":   PN = "11"  !CDS_PN = "11";
"NC4":   PN = "14"  !CDS_PN = "14";
"NO1":   PN = "3"  !CDS_PN = "3";
"NO2":   PN = "6"  !CDS_PN = "6";
"NO3":   PN = "10"  !CDS_PN = "10";
"NO4":   PN = "13"  !CDS_PN = "13";
BODY = "RESISTOR","I459": LOCATION = "R485" #&CDS_LOCATION = "R485" &SEC = "1" #&CDS_SEC = "1";
"1":   PN = "1"  !CDS_PN = "1";
"2":   PN = "2"  !CDS_PN = "2";
BODY = "RESISTOR","I460": LOCATION = "R486" #&CDS_LOCATION = "R486" &SEC = "1" #&CDS_SEC = "1";
"1":   PN = "1"  !CDS_PN = "1";
"2":   PN = "2"  !CDS_PN = "2";
BODY = "RESISTOR","I462": LOCATION = "R483" #&CDS_LOCATION = "R483" &SEC = "1" #&CDS_SEC = "1";
"1":   PN = "1"  !CDS_PN = "1";
"2":   PN = "2"  !CDS_PN = "2";
BODY = "RESISTOR","I463": LOCATION = "R484" #&CDS_LOCATION = "R484" &SEC = "1" #&CDS_SEC = "1";
"1":   PN = "1"  !CDS_PN = "1";
"2":   PN = "2"  !CDS_PN = "2";
BODY = "RESISTOR","I464": LOCATION = "R482" #&CDS_LOCATION = "R482" &SEC = "1" #&CDS_SEC = "1";
"1":   PN = "1"  !CDS_PN = "1";
"2":   PN = "2"  !CDS_PN = "2";
BODY = "RESISTOR","I466": LOCATION = "R474" #&CDS_LOCATION = "R474" &SEC = "1" #&CDS_SEC = "1";
"1":   PN = "1"  !CDS_PN = "1";
"2":   PN = "2"  !CDS_PN = "2";
BODY = "RESISTOR","I467": LOCATION = "R475" #&CDS_LOCATION = "R475" &SEC = "1" #&CDS_SEC = "1";
"1":   PN = "1"  !CDS_PN = "1";
"2":   PN = "2"  !CDS_PN = "2";
BODY = "RESISTOR","I468": LOCATION = "R476" #&CDS_LOCATION = "R476" &SEC = "1" #&CDS_SEC = "1";
"1":   PN = "1"  !CDS_PN = "1";
"2":   PN = "2"  !CDS_PN = "2";
BODY = "RESISTOR","I469": LOCATION = "R477" #&CDS_LOCATION = "R477" &SEC = "1" #&CDS_SEC = "1";
"1":   PN = "1"  !CDS_PN = "1";
"2":   PN = "2"  !CDS_PN = "2";
BODY = "TS3A5018PWR_TSSOP16","I473": LOCATION = "U30" #&CDS_LOCATION = "U30" &SEC = "2" #&CDS_SEC = "2";
"GND":   PN = "8"  !CDS_PN = "8";
"V_P":   PN = "16"  !CDS_PN = "16";
BODY = "CAPACITOR","I474": LOCATION = "C89" #&CDS_LOCATION = "C89" &SEC = "1" #&CDS_SEC = "1";
"1":   PN = "1"  !CDS_PN = "1";
"2":   PN = "2"  !CDS_PN = "2";
BODY = "CAPACITOR","I476": LOCATION = "C92" #&CDS_LOCATION = "C92" &SEC = "1" #&CDS_SEC = "1";
"1":   PN = "1"  !CDS_PN = "1";
"2":   PN = "2"  !CDS_PN = "2";
BODY = "TS3A5018PWR_TSSOP16","I478": LOCATION = "U37" #&CDS_LOCATION = "U37" &SEC = "2" #&CDS_SEC = "2";
"GND":   PN = "8"  !CDS_PN = "8";
"V_P":   PN = "16"  !CDS_PN = "16";
BODY = "TS3A5018PWR_TSSOP16","I481": LOCATION = "U38" #&CDS_LOCATION = "U38" &SEC = "2" #&CDS_SEC = "2";
"GND":   PN = "8"  !CDS_PN = "8";
"V_P":   PN = "16"  !CDS_PN = "16";
BODY = "CAPACITOR","I482": LOCATION = "C97" #&CDS_LOCATION = "C97" &SEC = "1" #&CDS_SEC = "1";
"1":   PN = "1"  !CDS_PN = "1";
"2":   PN = "2"  !CDS_PN = "2";
BODY = "NLASB3157DFT2G_SC88","I485": LOCATION = "U39" #&CDS_LOCATION = "U39" &SEC = "2" #&CDS_SEC = "2";
"GND":   PN = "2"  !CDS_PN = "2";
"VCC":   PN = "5"  !CDS_PN = "5";
BODY = "CAPACITOR","I486": LOCATION = "C123" #&CDS_LOCATION = "C123" &SEC = "1" #&CDS_SEC = "1";
"1":   PN = "1"  !CDS_PN = "1";
"2":   PN = "2"  !CDS_PN = "2";
BODY = "CAPACITOR","I490": LOCATION = "C102" #&CDS_LOCATION = "C102" &SEC = "1" #&CDS_SEC = "1";
"1":   PN = "1"  !CDS_PN = "1";
"2":   PN = "2"  !CDS_PN = "2";
BODY = "NLASB3157DFT2G_SC88","I491": LOCATION = "U40" #&CDS_LOCATION = "U40" &SEC = "2" #&CDS_SEC = "2";
"GND":   PN = "2"  !CDS_PN = "2";
"VCC":   PN = "5"  !CDS_PN = "5";
BODY = "RESISTOR","I493": LOCATION = "R464" #&CDS_LOCATION = "R464" &SEC = "1" #&CDS_SEC = "1";
"1":   PN = "1"  !CDS_PN = "1";
"2":   PN = "2"  !CDS_PN = "2";
BODY = "RESISTOR","I494": LOCATION = "R465" #&CDS_LOCATION = "R465" &SEC = "1" #&CDS_SEC = "1";
"1":   PN = "1"  !CDS_PN = "1";
"2":   PN = "2"  !CDS_PN = "2";
BODY = "CONN_USB_14P_GH4_F_RA_TH","I495": #LOCATION = "J13" !CDS_LOCATION = "J13" &SEC = "1" #&CDS_SEC = "1";
"CC1":   PN = "A5"  !CDS_PN = "A5";
"CC2":   PN = "B5"  !CDS_PN = "B5";
"D1_N":   PN = "A7"  !CDS_PN = "A7";
"D1_P":   PN = "A6"  !CDS_PN = "A6";
"D2_N":   PN = "B7"  !CDS_PN = "B7";
"D2_P":   PN = "B6"  !CDS_PN = "B6";
"GH1":   PN = "GH1"  !CDS_PN = "GH1";
"GH2":   PN = "GH2"  !CDS_PN = "GH2";
"GH3":   PN = "GH3"  !CDS_PN = "GH3";
"GH4":   PN = "GH4"  !CDS_PN = "GH4";
"GND_1":   PN = "A1"  !CDS_PN = "A1";
"GND_2":   PN = "A12"  !CDS_PN = "A12";
"GND_3":   PN = "B1"  !CDS_PN = "B1";
"GND_4":   PN = "B12"  !CDS_PN = "B12";
"VBUS_1":   PN = "A4"  !CDS_PN = "A4";
"VBUS_2":   PN = "A9"  !CDS_PN = "A9";
"VBUS_3":   PN = "B4"  !CDS_PN = "B4";
"VBUS_4":   PN = "B9"  !CDS_PN = "B9";
BODY = "RESISTOR","I497": #LOCATION = "R442" !CDS_LOCATION = "R442" &SEC = "1" #&CDS_SEC = "1";
"1":   PN = "1"  !CDS_PN = "1";
"2":   PN = "2"  !CDS_PN = "2";
DRAWING = "@timecard_lib.timecard(sch_1):page525";
BODY = "CAPACITOR","I7": LOCATION = "C284" #&CDS_LOCATION = "C284" &SEC = "1" #&CDS_SEC = "1";
"1":   PN = "1"  !CDS_PN = "1";
"2":   PN = "2"  !CDS_PN = "2";
BODY = "CAPACITOR","I8": LOCATION = "C298" #&CDS_LOCATION = "C298" &SEC = "1" #&CDS_SEC = "1";
"1":   PN = "1"  !CDS_PN = "1";
"2":   PN = "2"  !CDS_PN = "2";
BODY = "FERRITEBEAD","I10": LOCATION = "L23" #&CDS_LOCATION = "L23" &SEC = "1" #&CDS_SEC = "1";
"1":   PN = "1"  !CDS_PN = "1";
"2":   PN = "2"  !CDS_PN = "2";
BODY = "RESISTOR","I13": LOCATION = "R488" #&CDS_LOCATION = "R488" &SEC = "1" #&CDS_SEC = "1";
"1":   PN = "1"  !CDS_PN = "1";
"2":   PN = "2"  !CDS_PN = "2";
BODY = "CAPACITOR","I14": LOCATION = "C302" #&CDS_LOCATION = "C302" &SEC = "1" #&CDS_SEC = "1";
"1":   PN = "1"  !CDS_PN = "1";
"2":   PN = "2"  !CDS_PN = "2";
BODY = "CAPACITOR","I16": LOCATION = "C300" #&CDS_LOCATION = "C300" &SEC = "1" #&CDS_SEC = "1";
"1":   PN = "1"  !CDS_PN = "1";
"2":   PN = "2"  !CDS_PN = "2";
BODY = "CAPACITOR","I18": LOCATION = "C307" #&CDS_LOCATION = "C307" &SEC = "1" #&CDS_SEC = "1";
"1":   PN = "1"  !CDS_PN = "1";
"2":   PN = "2"  !CDS_PN = "2";
BODY = "CAPACITOR","I20": LOCATION = "C304" #&CDS_LOCATION = "C304" &SEC = "1" #&CDS_SEC = "1";
"1":   PN = "1"  !CDS_PN = "1";
"2":   PN = "2"  !CDS_PN = "2";
BODY = "ISL80101IRAJZ_DFN10","I29": LOCATION = "U41" #&CDS_LOCATION = "U41" &SEC = "1" #&CDS_SEC = "1";
"ENABLE":   PN = "7"  !CDS_PN = "7";
"GND":   PN = "5"  !CDS_PN = "5";
"NC":   PN = "8"  !CDS_PN = "8";
"PG":   PN = "4"  !CDS_PN = "4";
"SENSE/ADJ":   PN = "3"  !CDS_PN = "3";
"SS":   PN = "6"  !CDS_PN = "6";
"THRM_PAD":   PN = "11"  !CDS_PN = "11";
"VIN_1":   PN = "9"  !CDS_PN = "9";
"VIN_2":   PN = "10"  !CDS_PN = "10";
"VOUT_1":   PN = "1"  !CDS_PN = "1";
"VOUT_2":   PN = "2"  !CDS_PN = "2";
BODY = "CAPACITOR","I56": LOCATION = "C309" #&CDS_LOCATION = "C309" &SEC = "1" #&CDS_SEC = "1";
"1":   PN = "1"  !CDS_PN = "1";
"2":   PN = "2"  !CDS_PN = "2";
BODY = "CAPACITOR","I64": LOCATION = "C308" #&CDS_LOCATION = "C308" &SEC = "1" #&CDS_SEC = "1";
"1":   PN = "1"  !CDS_PN = "1";
"2":   PN = "2"  !CDS_PN = "2";
BODY = "RESISTOR","I65": LOCATION = "R487" #&CDS_LOCATION = "R487" &SEC = "1" #&CDS_SEC = "1";
"1":   PN = "1"  !CDS_PN = "1";
"2":   PN = "2"  !CDS_PN = "2";
BODY = "RESISTOR","I66": LOCATION = "R490" #&CDS_LOCATION = "R490" &SEC = "1" #&CDS_SEC = "1";
"1":   PN = "1"  !CDS_PN = "1";
"2":   PN = "2"  !CDS_PN = "2";
BODY = "RESISTOR","I67": LOCATION = "R491" #&CDS_LOCATION = "R491" &SEC = "1" #&CDS_SEC = "1";
"1":   PN = "1"  !CDS_PN = "1";
"2":   PN = "2"  !CDS_PN = "2";
BODY = "RESISTOR","I68": LOCATION = "R489" #&CDS_LOCATION = "R489" &SEC = "1" #&CDS_SEC = "1";
"1":   PN = "1"  !CDS_PN = "1";
"2":   PN = "2"  !CDS_PN = "2";
BODY = "DIODE_2F","I102": LOCATION = "CR1" #&CDS_LOCATION = "CR1" &SEC = "1" #&CDS_SEC = "1";
"A":   PN = "A"  !CDS_PN = "A";
"C":   PN = "C"  !CDS_PN = "C";
BODY = "DIODE_2F","I104": LOCATION = "CR2" #&CDS_LOCATION = "CR2" &SEC = "1" #&CDS_SEC = "1";
"A":   PN = "A"  !CDS_PN = "A";
"C":   PN = "C"  !CDS_PN = "C";
BODY = "FERRITEBEAD","I108": LOCATION = "L24" #&CDS_LOCATION = "L24" &SEC = "1" #&CDS_SEC = "1";
"1":   PN = "1"  !CDS_PN = "1";
"2":   PN = "2"  !CDS_PN = "2";
DRAWING = "@timecard_lib.timecard(sch_1):page527";
BODY = "CONN_USB_1X5_G2_GH4_F_RA_SMT","I2": LOCATION = "J11" #&CDS_LOCATION = "J11" &SEC = "1" #&CDS_SEC = "1";
"1":   PN = "1"  !CDS_PN = "1";
"2":   PN = "2"  !CDS_PN = "2";
"3":   PN = "3"  !CDS_PN = "3";
"4":   PN = "4"  !CDS_PN = "4";
"5":   PN = "5"  !CDS_PN = "5";
"G1":   PN = "G1"  !CDS_PN = "G1";
"G2":   PN = "G2"  !CDS_PN = "G2";
"GH1":   PN = "GH1"  !CDS_PN = "GH1";
"GH2":   PN = "GH2"  !CDS_PN = "GH2";
"GH3":   PN = "GH3"  !CDS_PN = "GH3";
"GH4":   PN = "GH4"  !CDS_PN = "GH4";
BODY = "CL1001485A","I4": LOCATION = "U9" #&CDS_LOCATION = "U9" &SEC = "1" #&CDS_SEC = "1";
"1":   PN = "1"  !CDS_PN = "1";
"2":   PN = "2"  !CDS_PN = "2";
"3":   PN = "3"  !CDS_PN = "3";
"4":   PN = "4"  !CDS_PN = "4";
"5":   PN = "5"  !CDS_PN = "5";
"6":   PN = "6"  !CDS_PN = "6";
BODY = "RESISTOR","I13": LOCATION = "R88" #&CDS_LOCATION = "R88" &SEC = "1" #&CDS_SEC = "1";
"1":   PN = "1"  !CDS_PN = "1";
"2":   PN = "2"  !CDS_PN = "2";
BODY = "RESISTOR","I14": LOCATION = "R87" #&CDS_LOCATION = "R87" &SEC = "1" #&CDS_SEC = "1";
"1":   PN = "1"  !CDS_PN = "1";
"2":   PN = "2"  !CDS_PN = "2";
BODY = "CAPACITOR","I15": LOCATION = "C63" #&CDS_LOCATION = "C63" &SEC = "1" #&CDS_SEC = "1";
"1":   PN = "1"  !CDS_PN = "1";
"2":   PN = "2"  !CDS_PN = "2";
BODY = "CAPACITOR","I16": LOCATION = "C61" #&CDS_LOCATION = "C61" &SEC = "1" #&CDS_SEC = "1";
"1":   PN = "1"  !CDS_PN = "1";
"2":   PN = "2"  !CDS_PN = "2";
BODY = "RESISTOR","I23": LOCATION = "R96" #&CDS_LOCATION = "R96" &SEC = "1" #&CDS_SEC = "1";
"1":   PN = "1"  !CDS_PN = "1";
"2":   PN = "2"  !CDS_PN = "2";
BODY = "RESISTOR","I29": LOCATION = "R86" #&CDS_LOCATION = "R86" &SEC = "1" #&CDS_SEC = "1";
"1":   PN = "1"  !CDS_PN = "1";
"2":   PN = "2"  !CDS_PN = "2";
BODY = "RESISTOR","I30": LOCATION = "R85" #&CDS_LOCATION = "R85" &SEC = "1" #&CDS_SEC = "1";
"1":   PN = "1"  !CDS_PN = "1";
"2":   PN = "2"  !CDS_PN = "2";
BODY = "RESISTOR","I31": LOCATION = "R84" #&CDS_LOCATION = "R84" &SEC = "1" #&CDS_SEC = "1";
"1":   PN = "1"  !CDS_PN = "1";
"2":   PN = "2"  !CDS_PN = "2";
BODY = "RESISTOR","I32": LOCATION = "R83" #&CDS_LOCATION = "R83" &SEC = "1" #&CDS_SEC = "1";
"1":   PN = "1"  !CDS_PN = "1";
"2":   PN = "2"  !CDS_PN = "2";
BODY = "RESISTOR","I33": LOCATION = "R90" #&CDS_LOCATION = "R90" &SEC = "1" #&CDS_SEC = "1";
"1":   PN = "1"  !CDS_PN = "1";
"2":   PN = "2"  !CDS_PN = "2";
BODY = "RESISTOR","I34": LOCATION = "R89" #&CDS_LOCATION = "R89" &SEC = "1" #&CDS_SEC = "1";
"1":   PN = "1"  !CDS_PN = "1";
"2":   PN = "2"  !CDS_PN = "2";
BODY = "CAPACITOR","I47": LOCATION = "C58" #&CDS_LOCATION = "C58" &SEC = "1" #&CDS_SEC = "1";
"1":   PN = "1"  !CDS_PN = "1";
"2":   PN = "2"  !CDS_PN = "2";
BODY = "CAPACITOR","I48": LOCATION = "C59" #&CDS_LOCATION = "C59" &SEC = "1" #&CDS_SEC = "1";
"1":   PN = "1"  !CDS_PN = "1";
"2":   PN = "2"  !CDS_PN = "2";
BODY = "CAPACITOR","I51": LOCATION = "C64" #&CDS_LOCATION = "C64" &SEC = "1" #&CDS_SEC = "1";
"1":   PN = "1"  !CDS_PN = "1";
"2":   PN = "2"  !CDS_PN = "2";
BODY = "RESISTOR","I52": LOCATION = "R95" #&CDS_LOCATION = "R95" &SEC = "1" #&CDS_SEC = "1";
"1":   PN = "1"  !CDS_PN = "1";
"2":   PN = "2"  !CDS_PN = "2";
BODY = "RESISTOR","I53": LOCATION = "R93" #&CDS_LOCATION = "R93" &SEC = "1" #&CDS_SEC = "1";
"1":   PN = "1"  !CDS_PN = "1";
"2":   PN = "2"  !CDS_PN = "2";
BODY = "RESISTOR","I54": LOCATION = "R94" #&CDS_LOCATION = "R94" &SEC = "1" #&CDS_SEC = "1";
"1":   PN = "1"  !CDS_PN = "1";
"2":   PN = "2"  !CDS_PN = "2";
BODY = "RESISTOR","I55": LOCATION = "R92" #&CDS_LOCATION = "R92" &SEC = "1" #&CDS_SEC = "1";
"1":   PN = "1"  !CDS_PN = "1";
"2":   PN = "2"  !CDS_PN = "2";
BODY = "CAPACITOR","I56": LOCATION = "C65" #&CDS_LOCATION = "C65" &SEC = "1" #&CDS_SEC = "1";
"1":   PN = "1"  !CDS_PN = "1";
"2":   PN = "2"  !CDS_PN = "2";
BODY = "CAPACITOR","I57": LOCATION = "C66" #&CDS_LOCATION = "C66" &SEC = "1" #&CDS_SEC = "1";
"1":   PN = "1"  !CDS_PN = "1";
"2":   PN = "2"  !CDS_PN = "2";
BODY = "CAPACITOR","I66": LOCATION = "C60" #&CDS_LOCATION = "C60" &SEC = "1" #&CDS_SEC = "1";
"1":   PN = "1"  !CDS_PN = "1";
"2":   PN = "2"  !CDS_PN = "2";
BODY = "CAPACITOR","I74": LOCATION = "C69" #&CDS_LOCATION = "C69" &SEC = "1" #&CDS_SEC = "1";
"1":   PN = "1"  !CDS_PN = "1";
"2":   PN = "2"  !CDS_PN = "2";
BODY = "CAPACITOR","I77": LOCATION = "C70" #&CDS_LOCATION = "C70" &SEC = "1" #&CDS_SEC = "1";
"1":   PN = "1"  !CDS_PN = "1";
"2":   PN = "2"  !CDS_PN = "2";
BODY = "TPS2051BDBVT_SOT23_5","I78": LOCATION = "U12" #&CDS_LOCATION = "U12" &SEC = "2" #&CDS_SEC = "2";
"GND":   PN = "2"  !CDS_PN = "2";
BODY = "TPS2051BDBVT_SOT23_5","I79": LOCATION = "U12" #&CDS_LOCATION = "U12" &SEC = "1" #&CDS_SEC = "1";
"EN":   PN = "4"  !CDS_PN = "4";
"IN":   PN = "5"  !CDS_PN = "5";
"OC*":   PN = "3"  !CDS_PN = "3";
"OUT":   PN = "1"  !CDS_PN = "1";
BODY = "RESISTOR","I83": LOCATION = "R107" #&CDS_LOCATION = "R107" &SEC = "1" #&CDS_SEC = "1";
"1":   PN = "1"  !CDS_PN = "1";
"2":   PN = "2"  !CDS_PN = "2";
BODY = "CAPACITOR","I85": LOCATION = "C71" #&CDS_LOCATION = "C71" &SEC = "1" #&CDS_SEC = "1";
"1":   PN = "1"  !CDS_PN = "1";
"2":   PN = "2"  !CDS_PN = "2";
BODY = "FERRITEBEAD","I91": LOCATION = "L3" #&CDS_LOCATION = "L3" &SEC = "1" #&CDS_SEC = "1";
"1":   PN = "1"  !CDS_PN = "1";
"2":   PN = "2"  !CDS_PN = "2";
BODY = "CAPACITOR","I93": LOCATION = "C62" #&CDS_LOCATION = "C62" &SEC = "1" #&CDS_SEC = "1";
"1":   PN = "1"  !CDS_PN = "1";
"2":   PN = "2"  !CDS_PN = "2";
BODY = "CAPACITOR","I103": LOCATION = "C67" #&CDS_LOCATION = "C67" &SEC = "1" #&CDS_SEC = "1";
"1":   PN = "1"  !CDS_PN = "1";
"2":   PN = "2"  !CDS_PN = "2";
BODY = "TS3USB3031RMGR_WQFN12","I108": LOCATION = "U11" #&CDS_LOCATION = "U11" &SEC = "1" #&CDS_SEC = "1";
"D_N":   PN = "10"  !CDS_PN = "10";
"D_P":   PN = "11"  !CDS_PN = "11";
"GND":   PN = "9"  !CDS_PN = "9";
"MHL_N":   PN = "8"  !CDS_PN = "8";
"MHL_P":   PN = "7"  !CDS_PN = "7";
"SEL0":   PN = "1"  !CDS_PN = "1";
"SEL1":   PN = "2"  !CDS_PN = "2";
"USB1_N":   PN = "4"  !CDS_PN = "4";
"USB1_P":   PN = "3"  !CDS_PN = "3";
"USB2_N":   PN = "6"  !CDS_PN = "6";
"USB2_P":   PN = "5"  !CDS_PN = "5";
"VCC":   PN = "12"  !CDS_PN = "12";
BODY = "RESISTOR","I123": LOCATION = "R105" #&CDS_LOCATION = "R105" &SEC = "1" #&CDS_SEC = "1";
"1":   PN = "1"  !CDS_PN = "1";
"2":   PN = "2"  !CDS_PN = "2";
BODY = "RESISTOR","I124": LOCATION = "R106" #&CDS_LOCATION = "R106" &SEC = "1" #&CDS_SEC = "1";
"1":   PN = "1"  !CDS_PN = "1";
"2":   PN = "2"  !CDS_PN = "2";
BODY = "RESISTOR","I126": LOCATION = "R104" #&CDS_LOCATION = "R104" &SEC = "1" #&CDS_SEC = "1";
"1":   PN = "1"  !CDS_PN = "1";
"2":   PN = "2"  !CDS_PN = "2";
BODY = "CAPACITOR","I144": LOCATION = "C68" #&CDS_LOCATION = "C68" &SEC = "1" #&CDS_SEC = "1";
"1":   PN = "1"  !CDS_PN = "1";
"2":   PN = "2"  !CDS_PN = "2";
BODY = "CL5003148A","I146": LOCATION = "U10" #&CDS_LOCATION = "U10" &SEC = "2" #&CDS_SEC = "2";
"GND":   PN = "3"  !CDS_PN = "3";
"VCC":   PN = "5"  !CDS_PN = "5";
BODY = "CL5003148A","I147": LOCATION = "U10" #&CDS_LOCATION = "U10" &SEC = "1" #&CDS_SEC = "1";
"A":   PN = "1"  !CDS_PN = "1";
"B":   PN = "2"  !CDS_PN = "2";
"Y":   PN = "4"  !CDS_PN = "4";
BODY = "RESISTOR","I149": LOCATION = "R99" #&CDS_LOCATION = "R99" &SEC = "1" #&CDS_SEC = "1";
"1":   PN = "1"  !CDS_PN = "1";
"2":   PN = "2"  !CDS_PN = "2";
BODY = "RESISTOR","I155": LOCATION = "R100" #&CDS_LOCATION = "R100" &SEC = "1" #&CDS_SEC = "1";
"1":   PN = "1"  !CDS_PN = "1";
"2":   PN = "2"  !CDS_PN = "2";
BODY = "RESISTOR","I175": LOCATION = "R98" #&CDS_LOCATION = "R98" &SEC = "1" #&CDS_SEC = "1";
"1":   PN = "1"  !CDS_PN = "1";
"2":   PN = "2"  !CDS_PN = "2";
BODY = "RESISTOR","I176": LOCATION = "R97" #&CDS_LOCATION = "R97" &SEC = "1" #&CDS_SEC = "1";
"1":   PN = "1"  !CDS_PN = "1";
"2":   PN = "2"  !CDS_PN = "2";
BODY = "RESISTOR","I187": LOCATION = "R91" #&CDS_LOCATION = "R91" &SEC = "1" #&CDS_SEC = "1";
"1":   PN = "1"  !CDS_PN = "1";
"2":   PN = "2"  !CDS_PN = "2";
BODY = "CONN_HDR_2X10_M_S_SMT","I193": LOCATION = "P1" #&CDS_LOCATION = "P1" &SEC = "1" #&CDS_SEC = "1";
"1":   PN = "1"  !CDS_PN = "1";
"2":   PN = "2"  !CDS_PN = "2";
"3":   PN = "3"  !CDS_PN = "3";
"4":   PN = "4"  !CDS_PN = "4";
"5":   PN = "5"  !CDS_PN = "5";
"6":   PN = "6"  !CDS_PN = "6";
"7":   PN = "7"  !CDS_PN = "7";
"8":   PN = "8"  !CDS_PN = "8";
"9":   PN = "9"  !CDS_PN = "9";
"10":   PN = "10"  !CDS_PN = "10";
"11":   PN = "11"  !CDS_PN = "11";
"12":   PN = "12"  !CDS_PN = "12";
"13":   PN = "13"  !CDS_PN = "13";
"14":   PN = "14"  !CDS_PN = "14";
"15":   PN = "15"  !CDS_PN = "15";
"16":   PN = "16"  !CDS_PN = "16";
"17":   PN = "17"  !CDS_PN = "17";
"18":   PN = "18"  !CDS_PN = "18";
"19":   PN = "19"  !CDS_PN = "19";
"20":   PN = "20"  !CDS_PN = "20";
BODY = "CONN_HDR_1X3_M_S_SMT","I198": LOCATION = "J18" #&CDS_LOCATION = "J18" &SEC = "1" #&CDS_SEC = "1";
"1":   PN = "1"  !CDS_PN = "1";
"2":   PN = "2"  !CDS_PN = "2";
"3":   PN = "3"  !CDS_PN = "3";
BODY = "RESISTOR","I200": LOCATION = "R101" #&CDS_LOCATION = "R101" &SEC = "1" #&CDS_SEC = "1";
"1":   PN = "1"  !CDS_PN = "1";
"2":   PN = "2"  !CDS_PN = "2";
BODY = "RESISTOR","I201": LOCATION = "R102" #&CDS_LOCATION = "R102" &SEC = "1" #&CDS_SEC = "1";
"1":   PN = "1"  !CDS_PN = "1";
"2":   PN = "2"  !CDS_PN = "2";
BODY = "RESISTOR","I202": LOCATION = "R103" #&CDS_LOCATION = "R103" &SEC = "1" #&CDS_SEC = "1";
"1":   PN = "1"  !CDS_PN = "1";
"2":   PN = "2"  !CDS_PN = "2";
BODY = "RESISTOR","I204": LOCATION = "R266" #&CDS_LOCATION = "R266" &SEC = "1" #&CDS_SEC = "1";
"1":   PN = "1"  !CDS_PN = "1";
"2":   PN = "2"  !CDS_PN = "2";
BODY = "RESISTOR","I206": LOCATION = "R267" #&CDS_LOCATION = "R267" &SEC = "1" #&CDS_SEC = "1";
"1":   PN = "1"  !CDS_PN = "1";
"2":   PN = "2"  !CDS_PN = "2";
BODY = "CAPACITOR","I208": LOCATION = "C282" #&CDS_LOCATION = "C282" &SEC = "1" #&CDS_SEC = "1";
"1":   PN = "1"  !CDS_PN = "1";
"2":   PN = "2"  !CDS_PN = "2";
BODY = "CAPACITOR","I209": LOCATION = "C283" #&CDS_LOCATION = "C283" &SEC = "1" #&CDS_SEC = "1";
"1":   PN = "1"  !CDS_PN = "1";
"2":   PN = "2"  !CDS_PN = "2";
BODY = "RESISTOR","I211": LOCATION = "R287" #&CDS_LOCATION = "R287" &SEC = "1" #&CDS_SEC = "1";
"1":   PN = "1"  !CDS_PN = "1";
"2":   PN = "2"  !CDS_PN = "2";
BODY = "NUT","I220": LOCATION = "MAC_PIN8" #&CDS_LOCATION = "MAC_PIN8" &SEC = "1" #&CDS_SEC = "1";
"1":   PN = "1"  !CDS_PN = "1";
BODY = "RESISTOR","I221": LOCATION = "R265" #&CDS_LOCATION = "R265" &SEC = "1" #&CDS_SEC = "1";
"1":   PN = "1"  !CDS_PN = "1";
"2":   PN = "2"  !CDS_PN = "2";
BODY = "RESISTOR","I222": LOCATION = "R264" #&CDS_LOCATION = "R264" &SEC = "1" #&CDS_SEC = "1";
"1":   PN = "1"  !CDS_PN = "1";
"2":   PN = "2"  !CDS_PN = "2";
BODY = "NUT","I224": LOCATION = "MAC_PIN7" #&CDS_LOCATION = "MAC_PIN7" &SEC = "1" #&CDS_SEC = "1";
"1":   PN = "1"  !CDS_PN = "1";
BODY = "NUT","I225": LOCATION = "MAC_PIN6" #&CDS_LOCATION = "MAC_PIN6" &SEC = "1" #&CDS_SEC = "1";
"1":   PN = "1"  !CDS_PN = "1";
BODY = "NUT","I226": LOCATION = "MAC_PIN3" #&CDS_LOCATION = "MAC_PIN3" &SEC = "1" #&CDS_SEC = "1";
"1":   PN = "1"  !CDS_PN = "1";
BODY = "NUT","I227": LOCATION = "MAC_PIN1" #&CDS_LOCATION = "MAC_PIN1" &SEC = "1" #&CDS_SEC = "1";
"1":   PN = "1"  !CDS_PN = "1";
BODY = "NUT","I228": LOCATION = "MAC_PIN4" #&CDS_LOCATION = "MAC_PIN4" &SEC = "1" #&CDS_SEC = "1";
"1":   PN = "1"  !CDS_PN = "1";
BODY = "NUT","I229": LOCATION = "MAC_PIN2" #&CDS_LOCATION = "MAC_PIN2" &SEC = "1" #&CDS_SEC = "1";
"1":   PN = "1"  !CDS_PN = "1";
BODY = "NUT","I230": LOCATION = "MAC_PIN5" #&CDS_LOCATION = "MAC_PIN5" &SEC = "1" #&CDS_SEC = "1";
"1":   PN = "1"  !CDS_PN = "1";
BODY = "POWERMOS_3P_PCH","I231": LOCATION = "Q3" #&CDS_LOCATION = "Q3" &SEC = "1" #&CDS_SEC = "1";
"D":   PN = "3"  !CDS_PN = "3";
"G":   PN = "1"  !CDS_PN = "1";
"S":   PN = "2"  !CDS_PN = "2";
BODY = "POWERMOS_3P_NCH_V1","I232": LOCATION = "Q2" #&CDS_LOCATION = "Q2" &SEC = "1" #&CDS_SEC = "1";
"D":   PN = "3"  !CDS_PN = "3";
"G":   PN = "1"  !CDS_PN = "1";
"S":   PN = "2"  !CDS_PN = "2";
BODY = "RESISTOR","I233": LOCATION = "R44" #&CDS_LOCATION = "R44" &SEC = "1" #&CDS_SEC = "1";
"1":   PN = "1"  !CDS_PN = "1";
"2":   PN = "2"  !CDS_PN = "2";
BODY = "RESISTOR","I240": LOCATION = "R81" #&CDS_LOCATION = "R81" &SEC = "1" #&CDS_SEC = "1";
"1":   PN = "1"  !CDS_PN = "1";
"2":   PN = "2"  !CDS_PN = "2";
BODY = "RESISTOR","I241": LOCATION = "R82" #&CDS_LOCATION = "R82" &SEC = "1" #&CDS_SEC = "1";
"1":   PN = "1"  !CDS_PN = "1";
"2":   PN = "2"  !CDS_PN = "2";
BODY = "FUSE","I244": LOCATION = "FU3" #&CDS_LOCATION = "FU3" &SEC = "1" #&CDS_SEC = "1";
"1":   PN = "1"  !CDS_PN = "1";
"2":   PN = "2"  !CDS_PN = "2";
BODY = "RESISTOR","I245": LOCATION = "R357" #&CDS_LOCATION = "R357" &SEC = "1" #&CDS_SEC = "1";
"1":   PN = "1"  !CDS_PN = "1";
"2":   PN = "2"  !CDS_PN = "2";
DRAWING = "@timecard_lib.timecard(sch_1):page16";
BODY = "TP_PIONT","I1014": LOCATION = "TP132" #&CDS_LOCATION = "TP132" &SEC = "1" #&CDS_SEC = "1";
"1":   PN = "1"  !CDS_PN = "1";
BODY = "TP_PIONT","I1015": LOCATION = "TP133" #&CDS_LOCATION = "TP133" &SEC = "1" #&CDS_SEC = "1";
"1":   PN = "1"  !CDS_PN = "1";
BODY = "TP_PIONT","I1016": LOCATION = "TP134" #&CDS_LOCATION = "TP134" &SEC = "1" #&CDS_SEC = "1";
"1":   PN = "1"  !CDS_PN = "1";
BODY = "TP_PIONT","I1017": LOCATION = "TP135" #&CDS_LOCATION = "TP135" &SEC = "1" #&CDS_SEC = "1";
"1":   PN = "1"  !CDS_PN = "1";
BODY = "TP_PIONT","I1018": LOCATION = "TP136" #&CDS_LOCATION = "TP136" &SEC = "1" #&CDS_SEC = "1";
"1":   PN = "1"  !CDS_PN = "1";
BODY = "TP_PIONT","I1019": LOCATION = "TP137" #&CDS_LOCATION = "TP137" &SEC = "1" #&CDS_SEC = "1";
"1":   PN = "1"  !CDS_PN = "1";
BODY = "TP_PIONT","I1020": LOCATION = "TP138" #&CDS_LOCATION = "TP138" &SEC = "1" #&CDS_SEC = "1";
"1":   PN = "1"  !CDS_PN = "1";
BODY = "TP_PIONT","I1021": LOCATION = "TP139" #&CDS_LOCATION = "TP139" &SEC = "1" #&CDS_SEC = "1";
"1":   PN = "1"  !CDS_PN = "1";
BODY = "TP_PIONT","I1022": LOCATION = "TP140" #&CDS_LOCATION = "TP140" &SEC = "1" #&CDS_SEC = "1";
"1":   PN = "1"  !CDS_PN = "1";
BODY = "TP_PIONT","I1023": LOCATION = "TP141" #&CDS_LOCATION = "TP141" &SEC = "1" #&CDS_SEC = "1";
"1":   PN = "1"  !CDS_PN = "1";
BODY = "TP_PIONT","I1206": LOCATION = "TP52" #&CDS_LOCATION = "TP52" &SEC = "1" #&CDS_SEC = "1";
"1":   PN = "1"  !CDS_PN = "1";
BODY = "TP_PIONT","I1208": LOCATION = "TP53" #&CDS_LOCATION = "TP53" &SEC = "1" #&CDS_SEC = "1";
"1":   PN = "1"  !CDS_PN = "1";
BODY = "TP_PIONT","I1210": LOCATION = "TP54" #&CDS_LOCATION = "TP54" &SEC = "1" #&CDS_SEC = "1";
"1":   PN = "1"  !CDS_PN = "1";
BODY = "TP_PIONT","I1212": LOCATION = "TP55" #&CDS_LOCATION = "TP55" &SEC = "1" #&CDS_SEC = "1";
"1":   PN = "1"  !CDS_PN = "1";
BODY = "TP_PIONT","I1215": LOCATION = "TP56" #&CDS_LOCATION = "TP56" &SEC = "1" #&CDS_SEC = "1";
"1":   PN = "1"  !CDS_PN = "1";
BODY = "TP_PIONT","I1217": LOCATION = "TP57" #&CDS_LOCATION = "TP57" &SEC = "1" #&CDS_SEC = "1";
"1":   PN = "1"  !CDS_PN = "1";
BODY = "TP_PIONT","I1219": LOCATION = "TP58" #&CDS_LOCATION = "TP58" &SEC = "1" #&CDS_SEC = "1";
"1":   PN = "1"  !CDS_PN = "1";
BODY = "TP_PIONT","I1233": LOCATION = "TP60" #&CDS_LOCATION = "TP60" &SEC = "1" #&CDS_SEC = "1";
"1":   PN = "1"  !CDS_PN = "1";
BODY = "TP_PIONT","I1487": LOCATION = "TP193" #&CDS_LOCATION = "TP193" &SEC = "1" #&CDS_SEC = "1";
"1":   PN = "1"  !CDS_PN = "1";
BODY = "TP_PIONT","I1488": LOCATION = "TP194" #&CDS_LOCATION = "TP194" &SEC = "1" #&CDS_SEC = "1";
"1":   PN = "1"  !CDS_PN = "1";
BODY = "TP_PIONT","I1489": LOCATION = "TP195" #&CDS_LOCATION = "TP195" &SEC = "1" #&CDS_SEC = "1";
"1":   PN = "1"  !CDS_PN = "1";
BODY = "TP_PIONT","I1490": LOCATION = "TP196" #&CDS_LOCATION = "TP196" &SEC = "1" #&CDS_SEC = "1";
"1":   PN = "1"  !CDS_PN = "1";
BODY = "TP_PIONT","I1505": LOCATION = "TP183" #&CDS_LOCATION = "TP183" &SEC = "1" #&CDS_SEC = "1";
"1":   PN = "1"  !CDS_PN = "1";
BODY = "TP_PIONT","I1506": LOCATION = "TP184" #&CDS_LOCATION = "TP184" &SEC = "1" #&CDS_SEC = "1";
"1":   PN = "1"  !CDS_PN = "1";
BODY = "TP_PIONT","I1507": LOCATION = "TP185" #&CDS_LOCATION = "TP185" &SEC = "1" #&CDS_SEC = "1";
"1":   PN = "1"  !CDS_PN = "1";
BODY = "TP_PIONT","I1508": LOCATION = "TP186" #&CDS_LOCATION = "TP186" &SEC = "1" #&CDS_SEC = "1";
"1":   PN = "1"  !CDS_PN = "1";
BODY = "TP_PIONT","I1509": LOCATION = "TP187" #&CDS_LOCATION = "TP187" &SEC = "1" #&CDS_SEC = "1";
"1":   PN = "1"  !CDS_PN = "1";
BODY = "TP_PIONT","I1510": LOCATION = "TP188" #&CDS_LOCATION = "TP188" &SEC = "1" #&CDS_SEC = "1";
"1":   PN = "1"  !CDS_PN = "1";
BODY = "TP_PIONT","I1511": LOCATION = "TP180" #&CDS_LOCATION = "TP180" &SEC = "1" #&CDS_SEC = "1";
"1":   PN = "1"  !CDS_PN = "1";
BODY = "TP_PIONT","I1512": LOCATION = "TP181" #&CDS_LOCATION = "TP181" &SEC = "1" #&CDS_SEC = "1";
"1":   PN = "1"  !CDS_PN = "1";
BODY = "TP_PIONT","I1513": LOCATION = "TP182" #&CDS_LOCATION = "TP182" &SEC = "1" #&CDS_SEC = "1";
"1":   PN = "1"  !CDS_PN = "1";
BODY = "TP_PIONT","I1516": LOCATION = "TP78" #&CDS_LOCATION = "TP78" &SEC = "1" #&CDS_SEC = "1";
"1":   PN = "1"  !CDS_PN = "1";
BODY = "TP_PIONT","I1523": LOCATION = "TP203" #&CDS_LOCATION = "TP203" &SEC = "1" #&CDS_SEC = "1";
"1":   PN = "1"  !CDS_PN = "1";
BODY = "TP_PIONT","I1524": LOCATION = "TP204" #&CDS_LOCATION = "TP204" &SEC = "1" #&CDS_SEC = "1";
"1":   PN = "1"  !CDS_PN = "1";
BODY = "TP_PIONT","I1527": LOCATION = "TP199" #&CDS_LOCATION = "TP199" &SEC = "1" #&CDS_SEC = "1";
"1":   PN = "1"  !CDS_PN = "1";
BODY = "TP_PIONT","I1528": LOCATION = "TP200" #&CDS_LOCATION = "TP200" &SEC = "1" #&CDS_SEC = "1";
"1":   PN = "1"  !CDS_PN = "1";
BODY = "TP_PIONT","I1529": LOCATION = "TP201" #&CDS_LOCATION = "TP201" &SEC = "1" #&CDS_SEC = "1";
"1":   PN = "1"  !CDS_PN = "1";
BODY = "TP_PIONT","I1530": LOCATION = "TP202" #&CDS_LOCATION = "TP202" &SEC = "1" #&CDS_SEC = "1";
"1":   PN = "1"  !CDS_PN = "1";
BODY = "RESISTOR","I1542": LOCATION = "R171" #&CDS_LOCATION = "R171" &SEC = "1" #&CDS_SEC = "1";
"1":   PN = "1"  !CDS_PN = "1";
"2":   PN = "2"  !CDS_PN = "2";
BODY = "RESISTOR","I1544": LOCATION = "R173" #&CDS_LOCATION = "R173" &SEC = "1" #&CDS_SEC = "1";
"1":   PN = "1"  !CDS_PN = "1";
"2":   PN = "2"  !CDS_PN = "2";
BODY = "RESISTOR","I1547": LOCATION = "R284" #&CDS_LOCATION = "R284" &SEC = "1" #&CDS_SEC = "1";
"1":   PN = "1"  !CDS_PN = "1";
"2":   PN = "2"  !CDS_PN = "2";
BODY = "RESISTOR","I1549": LOCATION = "R286" #&CDS_LOCATION = "R286" &SEC = "1" #&CDS_SEC = "1";
"1":   PN = "1"  !CDS_PN = "1";
"2":   PN = "2"  !CDS_PN = "2";
BODY = "RESISTOR","I1550": LOCATION = "R328" #&CDS_LOCATION = "R328" &SEC = "1" #&CDS_SEC = "1";
"1":   PN = "1"  !CDS_PN = "1";
"2":   PN = "2"  !CDS_PN = "2";
BODY = "RESISTOR","I1552": LOCATION = "R326" #&CDS_LOCATION = "R326" &SEC = "1" #&CDS_SEC = "1";
"1":   PN = "1"  !CDS_PN = "1";
"2":   PN = "2"  !CDS_PN = "2";
BODY = "RESISTOR","I1555": LOCATION = "R293" #&CDS_LOCATION = "R293" &SEC = "1" #&CDS_SEC = "1";
"1":   PN = "1"  !CDS_PN = "1";
"2":   PN = "2"  !CDS_PN = "2";
BODY = "RESISTOR","I1557": LOCATION = "R309" #&CDS_LOCATION = "R309" &SEC = "1" #&CDS_SEC = "1";
"1":   PN = "1"  !CDS_PN = "1";
"2":   PN = "2"  !CDS_PN = "2";
BODY = "RESISTOR","I1602": LOCATION = "R325" #&CDS_LOCATION = "R325" &SEC = "1" #&CDS_SEC = "1";
"1":   PN = "1"  !CDS_PN = "1";
"2":   PN = "2"  !CDS_PN = "2";
BODY = "RESISTOR","I1603": LOCATION = "R327" #&CDS_LOCATION = "R327" &SEC = "1" #&CDS_SEC = "1";
"1":   PN = "1"  !CDS_PN = "1";
"2":   PN = "2"  !CDS_PN = "2";
BODY = "RESISTOR","I1604": LOCATION = "R308" #&CDS_LOCATION = "R308" &SEC = "1" #&CDS_SEC = "1";
"1":   PN = "1"  !CDS_PN = "1";
"2":   PN = "2"  !CDS_PN = "2";
BODY = "RESISTOR","I1605": LOCATION = "R292" #&CDS_LOCATION = "R292" &SEC = "1" #&CDS_SEC = "1";
"1":   PN = "1"  !CDS_PN = "1";
"2":   PN = "2"  !CDS_PN = "2";
BODY = "RESISTOR","I1606": LOCATION = "R285" #&CDS_LOCATION = "R285" &SEC = "1" #&CDS_SEC = "1";
"1":   PN = "1"  !CDS_PN = "1";
"2":   PN = "2"  !CDS_PN = "2";
BODY = "RESISTOR","I1607": LOCATION = "R172" #&CDS_LOCATION = "R172" &SEC = "1" #&CDS_SEC = "1";
"1":   PN = "1"  !CDS_PN = "1";
"2":   PN = "2"  !CDS_PN = "2";
BODY = "RESISTOR","I1608": LOCATION = "R170" #&CDS_LOCATION = "R170" &SEC = "1" #&CDS_SEC = "1";
"1":   PN = "1"  !CDS_PN = "1";
"2":   PN = "2"  !CDS_PN = "2";
BODY = "RESISTOR","I1609": LOCATION = "R283" #&CDS_LOCATION = "R283" &SEC = "1" #&CDS_SEC = "1";
"1":   PN = "1"  !CDS_PN = "1";
"2":   PN = "2"  !CDS_PN = "2";
BODY = "TP_PIONT","I1610": LOCATION = "TP3" #&CDS_LOCATION = "TP3" &SEC = "1" #&CDS_SEC = "1";
"1":   PN = "1"  !CDS_PN = "1";
BODY = "TP_PIONT","I1612": LOCATION = "TP4" #&CDS_LOCATION = "TP4" &SEC = "1" #&CDS_SEC = "1";
"1":   PN = "1"  !CDS_PN = "1";
BODY = "CONN_HDR_2X6_F_S_SMT","I1614": #LOCATION = "J5" !CDS_LOCATION = "J5" &SEC = "1" #&CDS_SEC = "1";
"1":   PN = "1"  !CDS_PN = "1";
"2":   PN = "2"  !CDS_PN = "2";
"3":   PN = "3"  !CDS_PN = "3";
"4":   PN = "4"  !CDS_PN = "4";
"5":   PN = "5"  !CDS_PN = "5";
"6":   PN = "6"  !CDS_PN = "6";
"7":   PN = "7"  !CDS_PN = "7";
"8":   PN = "8"  !CDS_PN = "8";
"9":   PN = "9"  !CDS_PN = "9";
"10":   PN = "10"  !CDS_PN = "10";
"11":   PN = "11"  !CDS_PN = "11";
"12":   PN = "12"  !CDS_PN = "12";
BODY = "TP_PIONT","I1615": LOCATION = "TP20" #&CDS_LOCATION = "TP20" &SEC = "1" #&CDS_SEC = "1";
"1":   PN = "1"  !CDS_PN = "1";
BODY = "TP_PIONT","I1626": LOCATION = "TP11" #&CDS_LOCATION = "TP11" &SEC = "1" #&CDS_SEC = "1";
"1":   PN = "1"  !CDS_PN = "1";
BODY = "TP_PIONT","I1627": LOCATION = "TP12" #&CDS_LOCATION = "TP12" &SEC = "1" #&CDS_SEC = "1";
"1":   PN = "1"  !CDS_PN = "1";
BODY = "TP_PIONT","I1628": LOCATION = "TP13" #&CDS_LOCATION = "TP13" &SEC = "1" #&CDS_SEC = "1";
"1":   PN = "1"  !CDS_PN = "1";
BODY = "TP_PIONT","I1629": LOCATION = "TP14" #&CDS_LOCATION = "TP14" &SEC = "1" #&CDS_SEC = "1";
"1":   PN = "1"  !CDS_PN = "1";
BODY = "TP_PIONT","I1630": LOCATION = "TP15" #&CDS_LOCATION = "TP15" &SEC = "1" #&CDS_SEC = "1";
"1":   PN = "1"  !CDS_PN = "1";
BODY = "TP_PIONT","I1631": LOCATION = "TP16" #&CDS_LOCATION = "TP16" &SEC = "1" #&CDS_SEC = "1";
"1":   PN = "1"  !CDS_PN = "1";
BODY = "TP_PIONT","I1632": LOCATION = "TP17" #&CDS_LOCATION = "TP17" &SEC = "1" #&CDS_SEC = "1";
"1":   PN = "1"  !CDS_PN = "1";
BODY = "TP_PIONT","I1633": LOCATION = "TP18" #&CDS_LOCATION = "TP18" &SEC = "1" #&CDS_SEC = "1";
"1":   PN = "1"  !CDS_PN = "1";
BODY = "TP_PIONT","I1634": LOCATION = "TP19" #&CDS_LOCATION = "TP19" &SEC = "1" #&CDS_SEC = "1";
"1":   PN = "1"  !CDS_PN = "1";
BODY = "TP_PIONT","I1645": LOCATION = "TP21" #&CDS_LOCATION = "TP21" &SEC = "1" #&CDS_SEC = "1";
"1":   PN = "1"  !CDS_PN = "1";
BODY = "TP_PIONT","I1646": LOCATION = "TP22" #&CDS_LOCATION = "TP22" &SEC = "1" #&CDS_SEC = "1";
"1":   PN = "1"  !CDS_PN = "1";
BODY = "TP_PIONT","I1647": LOCATION = "TP23" #&CDS_LOCATION = "TP23" &SEC = "1" #&CDS_SEC = "1";
"1":   PN = "1"  !CDS_PN = "1";
BODY = "TP_PIONT","I1648": LOCATION = "TP24" #&CDS_LOCATION = "TP24" &SEC = "1" #&CDS_SEC = "1";
"1":   PN = "1"  !CDS_PN = "1";
BODY = "TP_PIONT","I1649": LOCATION = "TP25" #&CDS_LOCATION = "TP25" &SEC = "1" #&CDS_SEC = "1";
"1":   PN = "1"  !CDS_PN = "1";
BODY = "TP_PIONT","I1650": LOCATION = "TP36" #&CDS_LOCATION = "TP36" &SEC = "1" #&CDS_SEC = "1";
"1":   PN = "1"  !CDS_PN = "1";
BODY = "TP_PIONT","I1651": LOCATION = "TP38" #&CDS_LOCATION = "TP38" &SEC = "1" #&CDS_SEC = "1";
"1":   PN = "1"  !CDS_PN = "1";
BODY = "TP_PIONT","I1652": LOCATION = "TP39" #&CDS_LOCATION = "TP39" &SEC = "1" #&CDS_SEC = "1";
"1":   PN = "1"  !CDS_PN = "1";
BODY = "TP_PIONT","I1653": LOCATION = "TP40" #&CDS_LOCATION = "TP40" &SEC = "1" #&CDS_SEC = "1";
"1":   PN = "1"  !CDS_PN = "1";
BODY = "TP_PIONT","I1654": LOCATION = "TP41" #&CDS_LOCATION = "TP41" &SEC = "1" #&CDS_SEC = "1";
"1":   PN = "1"  !CDS_PN = "1";
BODY = "TP_PIONT","I1660": LOCATION = "TP26" #&CDS_LOCATION = "TP26" &SEC = "1" #&CDS_SEC = "1";
"1":   PN = "1"  !CDS_PN = "1";
BODY = "TP_PIONT","I1661": LOCATION = "TP27" #&CDS_LOCATION = "TP27" &SEC = "1" #&CDS_SEC = "1";
"1":   PN = "1"  !CDS_PN = "1";
BODY = "TP_PIONT","I1662": LOCATION = "TP32" #&CDS_LOCATION = "TP32" &SEC = "1" #&CDS_SEC = "1";
"1":   PN = "1"  !CDS_PN = "1";
BODY = "TP_PIONT","I1663": LOCATION = "TP59" #&CDS_LOCATION = "TP59" &SEC = "1" #&CDS_SEC = "1";
"1":   PN = "1"  !CDS_PN = "1";
BODY = "TP_PIONT","I1665": LOCATION = "TP42" #&CDS_LOCATION = "TP42" &SEC = "1" #&CDS_SEC = "1";
"1":   PN = "1"  !CDS_PN = "1";
BODY = "TP_PIONT","I1667": LOCATION = "TP28" #&CDS_LOCATION = "TP28" &SEC = "1" #&CDS_SEC = "1";
"1":   PN = "1"  !CDS_PN = "1";
BODY = "TP_PIONT","I1669": LOCATION = "TP33" #&CDS_LOCATION = "TP33" &SEC = "1" #&CDS_SEC = "1";
"1":   PN = "1"  !CDS_PN = "1";
BODY = "TP_PIONT","I1672": LOCATION = "TP29" #&CDS_LOCATION = "TP29" &SEC = "1" #&CDS_SEC = "1";
"1":   PN = "1"  !CDS_PN = "1";
BODY = "TP_PIONT","I1673": LOCATION = "TP34" #&CDS_LOCATION = "TP34" &SEC = "1" #&CDS_SEC = "1";
"1":   PN = "1"  !CDS_PN = "1";
BODY = "TP_PIONT","I1675": LOCATION = "TP35" #&CDS_LOCATION = "TP35" &SEC = "1" #&CDS_SEC = "1";
"1":   PN = "1"  !CDS_PN = "1";
BODY = "TP_PIONT","I1678": LOCATION = "TP30" #&CDS_LOCATION = "TP30" &SEC = "1" #&CDS_SEC = "1";
"1":   PN = "1"  !CDS_PN = "1";
BODY = "TP_PIONT","I1679": LOCATION = "TP31" #&CDS_LOCATION = "TP31" &SEC = "1" #&CDS_SEC = "1";
"1":   PN = "1"  !CDS_PN = "1";
BODY = "TP_PIONT","I1682": LOCATION = "TP37" #&CDS_LOCATION = "TP37" &SEC = "1" #&CDS_SEC = "1";
"1":   PN = "1"  !CDS_PN = "1";
BODY = "TP_PIONT","I1684": LOCATION = "TP46" #&CDS_LOCATION = "TP46" &SEC = "1" #&CDS_SEC = "1";
"1":   PN = "1"  !CDS_PN = "1";
BODY = "TP_PIONT","I1689": LOCATION = "TP44" #&CDS_LOCATION = "TP44" &SEC = "1" #&CDS_SEC = "1";
"1":   PN = "1"  !CDS_PN = "1";
BODY = "TP_PIONT","I1690": LOCATION = "TP45" #&CDS_LOCATION = "TP45" &SEC = "1" #&CDS_SEC = "1";
"1":   PN = "1"  !CDS_PN = "1";
BODY = "TP_PIONT","I1691": LOCATION = "TP43" #&CDS_LOCATION = "TP43" &SEC = "1" #&CDS_SEC = "1";
"1":   PN = "1"  !CDS_PN = "1";
BODY = "TP_PIONT","I1693": LOCATION = "TP47" #&CDS_LOCATION = "TP47" &SEC = "1" #&CDS_SEC = "1";
"1":   PN = "1"  !CDS_PN = "1";
BODY = "TP_PIONT","I1695": LOCATION = "TP48" #&CDS_LOCATION = "TP48" &SEC = "1" #&CDS_SEC = "1";
"1":   PN = "1"  !CDS_PN = "1";
BODY = "TP_PIONT","I1699": LOCATION = "TP49" #&CDS_LOCATION = "TP49" &SEC = "1" #&CDS_SEC = "1";
"1":   PN = "1"  !CDS_PN = "1";
BODY = "TP_PIONT","I1701": LOCATION = "TP50" #&CDS_LOCATION = "TP50" &SEC = "1" #&CDS_SEC = "1";
"1":   PN = "1"  !CDS_PN = "1";
BODY = "TP_PIONT","I1704": LOCATION = "TP51" #&CDS_LOCATION = "TP51" &SEC = "1" #&CDS_SEC = "1";
"1":   PN = "1"  !CDS_PN = "1";
BODY = "TP_PIONT","I1705": LOCATION = "TP62" #&CDS_LOCATION = "TP62" &SEC = "1" #&CDS_SEC = "1";
"1":   PN = "1"  !CDS_PN = "1";
BODY = "RESISTOR","I1706": LOCATION = "R430" #&CDS_LOCATION = "R430" &SEC = "1" #&CDS_SEC = "1";
"1":   PN = "1"  !CDS_PN = "1";
"2":   PN = "2"  !CDS_PN = "2";
BODY = "RESISTOR","I1707": LOCATION = "R329" #&CDS_LOCATION = "R329" &SEC = "1" #&CDS_SEC = "1";
"1":   PN = "1"  !CDS_PN = "1";
"2":   PN = "2"  !CDS_PN = "2";
BODY = "RESISTOR","I1708": LOCATION = "R428" #&CDS_LOCATION = "R428" &SEC = "1" #&CDS_SEC = "1";
"1":   PN = "1"  !CDS_PN = "1";
"2":   PN = "2"  !CDS_PN = "2";
BODY = "RESISTOR","I1709": LOCATION = "R429" #&CDS_LOCATION = "R429" &SEC = "1" #&CDS_SEC = "1";
"1":   PN = "1"  !CDS_PN = "1";
"2":   PN = "2"  !CDS_PN = "2";
BODY = "RESISTOR","I1718": LOCATION = "R431" #&CDS_LOCATION = "R431" &SEC = "1" #&CDS_SEC = "1";
"1":   PN = "1"  !CDS_PN = "1";
"2":   PN = "2"  !CDS_PN = "2";
BODY = "RESISTOR","I1719": LOCATION = "R432" #&CDS_LOCATION = "R432" &SEC = "1" #&CDS_SEC = "1";
"1":   PN = "1"  !CDS_PN = "1";
"2":   PN = "2"  !CDS_PN = "2";
BODY = "RESISTOR","I1720": LOCATION = "R433" #&CDS_LOCATION = "R433" &SEC = "1" #&CDS_SEC = "1";
"1":   PN = "1"  !CDS_PN = "1";
"2":   PN = "2"  !CDS_PN = "2";
BODY = "RESISTOR","I1721": LOCATION = "R434" #&CDS_LOCATION = "R434" &SEC = "1" #&CDS_SEC = "1";
"1":   PN = "1"  !CDS_PN = "1";
"2":   PN = "2"  !CDS_PN = "2";
DRAWING = "@timecard_lib.timecard(sch_1):page7";
BODY = "RESISTOR","I3": LOCATION = "R64" #&CDS_LOCATION = "R64" &SEC = "1" #&CDS_SEC = "1";
"1":   PN = "1"  !CDS_PN = "1";
"2":   PN = "2"  !CDS_PN = "2";
BODY = "RESISTOR","I4": LOCATION = "R65" #&CDS_LOCATION = "R65" &SEC = "1" #&CDS_SEC = "1";
"1":   PN = "1"  !CDS_PN = "1";
"2":   PN = "2"  !CDS_PN = "2";
BODY = "RESISTOR","I7": LOCATION = "R69" #&CDS_LOCATION = "R69" &SEC = "1" #&CDS_SEC = "1";
"1":   PN = "1"  !CDS_PN = "1";
"2":   PN = "2"  !CDS_PN = "2";
BODY = "RESISTOR","I8": LOCATION = "R68" #&CDS_LOCATION = "R68" &SEC = "1" #&CDS_SEC = "1";
"1":   PN = "1"  !CDS_PN = "1";
"2":   PN = "2"  !CDS_PN = "2";
BODY = "RESISTOR","I13": LOCATION = "R67" #&CDS_LOCATION = "R67" &SEC = "1" #&CDS_SEC = "1";
"1":   PN = "1"  !CDS_PN = "1";
"2":   PN = "2"  !CDS_PN = "2";
BODY = "RESISTOR","I14": LOCATION = "R66" #&CDS_LOCATION = "R66" &SEC = "1" #&CDS_SEC = "1";
"1":   PN = "1"  !CDS_PN = "1";
"2":   PN = "2"  !CDS_PN = "2";
BODY = "CAPACITOR","I18": LOCATION = "C40" #&CDS_LOCATION = "C40" &SEC = "1" #&CDS_SEC = "1";
"1":   PN = "1"  !CDS_PN = "1";
"2":   PN = "2"  !CDS_PN = "2";
BODY = "CAPACITOR","I19": LOCATION = "C275" #&CDS_LOCATION = "C275" &SEC = "1" #&CDS_SEC = "1";
"1":   PN = "1"  !CDS_PN = "1";
"2":   PN = "2"  !CDS_PN = "2";
BODY = "FERRITEBEAD","I21": LOCATION = "L17" #&CDS_LOCATION = "L17" &SEC = "1" #&CDS_SEC = "1";
"1":   PN = "1"  !CDS_PN = "1";
"2":   PN = "2"  !CDS_PN = "2";
BODY = "CAPACITOR","I23": LOCATION = "C274" #&CDS_LOCATION = "C274" &SEC = "1" #&CDS_SEC = "1";
"1":   PN = "1"  !CDS_PN = "1";
"2":   PN = "2"  !CDS_PN = "2";
BODY = "RESISTOR","I33": LOCATION = "R298" #&CDS_LOCATION = "R298" &SEC = "1" #&CDS_SEC = "1";
"1":   PN = "1"  !CDS_PN = "1";
"2":   PN = "2"  !CDS_PN = "2";
BODY = "RESISTOR","I38": #LOCATION = "R296" !CDS_LOCATION = "R296" &SEC = "1" #&CDS_SEC = "1";
"1":   PN = "1"  !CDS_PN = "1";
"2":   PN = "2"  !CDS_PN = "2";
BODY = "RESISTOR","I39": #LOCATION = "R297" !CDS_LOCATION = "R297" &SEC = "1" #&CDS_SEC = "1";
"1":   PN = "1"  !CDS_PN = "1";
"2":   PN = "2"  !CDS_PN = "2";
BODY = "RESISTOR","I40": LOCATION = "R299" #&CDS_LOCATION = "R299" &SEC = "1" #&CDS_SEC = "1";
"1":   PN = "1"  !CDS_PN = "1";
"2":   PN = "2"  !CDS_PN = "2";
BODY = "RESISTOR","I41": LOCATION = "R300" #&CDS_LOCATION = "R300" &SEC = "1" #&CDS_SEC = "1";
"1":   PN = "1"  !CDS_PN = "1";
"2":   PN = "2"  !CDS_PN = "2";
BODY = "SHT31A_DIS_B10KS_DFN8","I44": LOCATION = "U27" #&CDS_LOCATION = "U27" &SEC = "1" #&CDS_SEC = "1";
"ADDR":   PN = "2"  !CDS_PN = "2";
"ALERT":   PN = "3"  !CDS_PN = "3";
"R":   PN = "7"  !CDS_PN = "7";
"RESET*":   PN = "6"  !CDS_PN = "6";
"SCL":   PN = "4"  !CDS_PN = "4";
"SDA":   PN = "1"  !CDS_PN = "1";
"THRM_PAD":   PN = "9"  !CDS_PN = "9";
"VDD":   PN = "5"  !CDS_PN = "5";
"VSS":   PN = "8"  !CDS_PN = "8";
DRAWING = "@timecard_lib.timecard(sch_1):page11";
BODY = "RESISTOR","I5": LOCATION = "R111" #&CDS_LOCATION = "R111" &SEC = "1" #&CDS_SEC = "1";
"1":   PN = "1"  !CDS_PN = "1";
"2":   PN = "2"  !CDS_PN = "2";
BODY = "RESISTOR","I7": LOCATION = "R113" #&CDS_LOCATION = "R113" &SEC = "1" #&CDS_SEC = "1";
"1":   PN = "1"  !CDS_PN = "1";
"2":   PN = "2"  !CDS_PN = "2";
BODY = "RESISTOR","I8": LOCATION = "R112" #&CDS_LOCATION = "R112" &SEC = "1" #&CDS_SEC = "1";
"1":   PN = "1"  !CDS_PN = "1";
"2":   PN = "2"  !CDS_PN = "2";
BODY = "RESISTOR","I11": LOCATION = "R109" #&CDS_LOCATION = "R109" &SEC = "1" #&CDS_SEC = "1";
"1":   PN = "1"  !CDS_PN = "1";
"2":   PN = "2"  !CDS_PN = "2";
BODY = "CAPACITOR","I12": LOCATION = "C72" #&CDS_LOCATION = "C72" &SEC = "1" #&CDS_SEC = "1";
"1":   PN = "1"  !CDS_PN = "1";
"2":   PN = "2"  !CDS_PN = "2";
BODY = "CAPACITOR","I13": LOCATION = "C73" #&CDS_LOCATION = "C73" &SEC = "1" #&CDS_SEC = "1";
"1":   PN = "1"  !CDS_PN = "1";
"2":   PN = "2"  !CDS_PN = "2";
BODY = "CAPACITOR","I15": LOCATION = "C78" #&CDS_LOCATION = "C78" &SEC = "1" #&CDS_SEC = "1";
"1":   PN = "1"  !CDS_PN = "1";
"2":   PN = "2"  !CDS_PN = "2";
BODY = "RESISTOR","I18": LOCATION = "R114" #&CDS_LOCATION = "R114" &SEC = "1" #&CDS_SEC = "1";
"1":   PN = "1"  !CDS_PN = "1";
"2":   PN = "2"  !CDS_PN = "2";
BODY = "RESISTOR","I20": LOCATION = "R117" #&CDS_LOCATION = "R117" &SEC = "1" #&CDS_SEC = "1";
"1":   PN = "1"  !CDS_PN = "1";
"2":   PN = "2"  !CDS_PN = "2";
BODY = "RESISTOR","I21": LOCATION = "R115" #&CDS_LOCATION = "R115" &SEC = "1" #&CDS_SEC = "1";
"1":   PN = "1"  !CDS_PN = "1";
"2":   PN = "2"  !CDS_PN = "2";
BODY = "CAPACITOR","I24": LOCATION = "C79" #&CDS_LOCATION = "C79" &SEC = "1" #&CDS_SEC = "1";
"1":   PN = "1"  !CDS_PN = "1";
"2":   PN = "2"  !CDS_PN = "2";
BODY = "RESISTOR","I25": LOCATION = "R116" #&CDS_LOCATION = "R116" &SEC = "1" #&CDS_SEC = "1";
"1":   PN = "1"  !CDS_PN = "1";
"2":   PN = "2"  !CDS_PN = "2";
BODY = "CAPACITOR","I26": LOCATION = "C80" #&CDS_LOCATION = "C80" &SEC = "1" #&CDS_SEC = "1";
"1":   PN = "1"  !CDS_PN = "1";
"2":   PN = "2"  !CDS_PN = "2";
BODY = "RESISTOR","I29": LOCATION = "R110" #&CDS_LOCATION = "R110" &SEC = "1" #&CDS_SEC = "1";
"1":   PN = "1"  !CDS_PN = "1";
"2":   PN = "2"  !CDS_PN = "2";
BODY = "CONN_HDR_2X4_F_S_SMT","I36": #LOCATION = "P2" !CDS_LOCATION = "P2" &SEC = "1" #&CDS_SEC = "1";
"1":   PN = "1"  !CDS_PN = "1";
"2":   PN = "2"  !CDS_PN = "2";
"3":   PN = "3"  !CDS_PN = "3";
"4":   PN = "4"  !CDS_PN = "4";
"5":   PN = "5"  !CDS_PN = "5";
"6":   PN = "6"  !CDS_PN = "6";
"7":   PN = "7"  !CDS_PN = "7";
"8":   PN = "8"  !CDS_PN = "8";
BODY = "RESISTOR","I38": LOCATION = "R268" #&CDS_LOCATION = "R268" &SEC = "1" #&CDS_SEC = "1";
"1":   PN = "1"  !CDS_PN = "1";
"2":   PN = "2"  !CDS_PN = "2";
BODY = "RESISTOR","I40": LOCATION = "R269" #&CDS_LOCATION = "R269" &SEC = "1" #&CDS_SEC = "1";
"1":   PN = "1"  !CDS_PN = "1";
"2":   PN = "2"  !CDS_PN = "2";
BODY = "CAPACITOR","I43": LOCATION = "C81" #&CDS_LOCATION = "C81" &SEC = "1" #&CDS_SEC = "1";
"1":   PN = "1"  !CDS_PN = "1";
"2":   PN = "2"  !CDS_PN = "2";
BODY = "CAPACITOR","I44": LOCATION = "C272" #&CDS_LOCATION = "C272" &SEC = "1" #&CDS_SEC = "1";
"1":   PN = "1"  !CDS_PN = "1";
"2":   PN = "2"  !CDS_PN = "2";
BODY = "CAPACITOR","I45": LOCATION = "C273" #&CDS_LOCATION = "C273" &SEC = "1" #&CDS_SEC = "1";
"1":   PN = "1"  !CDS_PN = "1";
"2":   PN = "2"  !CDS_PN = "2";
BODY = "FERRITEBEAD","I55": #LOCATION = "L16" !CDS_LOCATION = "L16" &SEC = "1" #&CDS_SEC = "1";
"1":   PN = "1"  !CDS_PN = "1";
"2":   PN = "2"  !CDS_PN = "2";
BODY = "FERRITEBEAD","I56": #LOCATION = "L15" !CDS_LOCATION = "L15" &SEC = "1" #&CDS_SEC = "1";
"1":   PN = "1"  !CDS_PN = "1";
"2":   PN = "2"  !CDS_PN = "2";
DRAWING = "@timecard_lib.timecard(sch_1):page68";
BODY = "RESISTOR","I2": LOCATION = "R165" #&CDS_LOCATION = "R165" &SEC = "1" #&CDS_SEC = "1";
"1":   PN = "1"  !CDS_PN = "1";
"2":   PN = "2"  !CDS_PN = "2";
BODY = "CAPACITOR","I3": LOCATION = "C184" #&CDS_LOCATION = "C184" &SEC = "1" #&CDS_SEC = "1";
"1":   PN = "1"  !CDS_PN = "1";
"2":   PN = "2"  !CDS_PN = "2";
BODY = "CAPACITOR","I5": LOCATION = "C190" #&CDS_LOCATION = "C190" &SEC = "1" #&CDS_SEC = "1";
"1":   PN = "1"  !CDS_PN = "1";
"2":   PN = "2"  !CDS_PN = "2";
BODY = "ISL80101IRAJZ_DFN10","I6": LOCATION = "U20" #&CDS_LOCATION = "U20" &SEC = "1" #&CDS_SEC = "1";
"ENABLE":   PN = "7"  !CDS_PN = "7";
"GND":   PN = "5"  !CDS_PN = "5";
"NC":   PN = "8"  !CDS_PN = "8";
"PG":   PN = "4"  !CDS_PN = "4";
"SENSE/ADJ":   PN = "3"  !CDS_PN = "3";
"SS":   PN = "6"  !CDS_PN = "6";
"THRM_PAD":   PN = "11"  !CDS_PN = "11";
"VIN_1":   PN = "9"  !CDS_PN = "9";
"VIN_2":   PN = "10"  !CDS_PN = "10";
"VOUT_1":   PN = "1"  !CDS_PN = "1";
"VOUT_2":   PN = "2"  !CDS_PN = "2";
BODY = "CAPACITOR","I9": LOCATION = "C192" #&CDS_LOCATION = "C192" &SEC = "1" #&CDS_SEC = "1";
"1":   PN = "1"  !CDS_PN = "1";
"2":   PN = "2"  !CDS_PN = "2";
BODY = "RESISTOR","I10": LOCATION = "R181" #&CDS_LOCATION = "R181" &SEC = "1" #&CDS_SEC = "1";
"1":   PN = "1"  !CDS_PN = "1";
"2":   PN = "2"  !CDS_PN = "2";
BODY = "RESISTOR","I11": LOCATION = "R178" #&CDS_LOCATION = "R178" &SEC = "1" #&CDS_SEC = "1";
"1":   PN = "1"  !CDS_PN = "1";
"2":   PN = "2"  !CDS_PN = "2";
BODY = "RESISTOR","I14": LOCATION = "R186" #&CDS_LOCATION = "R186" &SEC = "1" #&CDS_SEC = "1";
"1":   PN = "1"  !CDS_PN = "1";
"2":   PN = "2"  !CDS_PN = "2";
BODY = "RESISTOR","I16": LOCATION = "R189" #&CDS_LOCATION = "R189" &SEC = "1" #&CDS_SEC = "1";
"1":   PN = "1"  !CDS_PN = "1";
"2":   PN = "2"  !CDS_PN = "2";
BODY = "RESISTOR","I18": LOCATION = "R140" #&CDS_LOCATION = "R140" &SEC = "1" #&CDS_SEC = "1";
"1":   PN = "1"  !CDS_PN = "1";
"2":   PN = "2"  !CDS_PN = "2";
BODY = "FERRITEBEAD","I25": LOCATION = "L11" #&CDS_LOCATION = "L11" &SEC = "1" #&CDS_SEC = "1";
"1":   PN = "1"  !CDS_PN = "1";
"2":   PN = "2"  !CDS_PN = "2";
BODY = "RESISTOR","I26": LOCATION = "R177" #&CDS_LOCATION = "R177" &SEC = "1" #&CDS_SEC = "1";
"1":   PN = "1"  !CDS_PN = "1";
"2":   PN = "2"  !CDS_PN = "2";
BODY = "CAPACITOR","I27": LOCATION = "C185" #&CDS_LOCATION = "C185" &SEC = "1" #&CDS_SEC = "1";
"1":   PN = "1"  !CDS_PN = "1";
"2":   PN = "2"  !CDS_PN = "2";
BODY = "CAPACITOR","I35": LOCATION = "C188" #&CDS_LOCATION = "C188" &SEC = "1" #&CDS_SEC = "1";
"1":   PN = "1"  !CDS_PN = "1";
"2":   PN = "2"  !CDS_PN = "2";
BODY = "RESISTOR","I42": LOCATION = "R141" #&CDS_LOCATION = "R141" &SEC = "1" #&CDS_SEC = "1";
"1":   PN = "1"  !CDS_PN = "1";
"2":   PN = "2"  !CDS_PN = "2";
BODY = "FERRITEBEAD","I43": LOCATION = "L6" #&CDS_LOCATION = "L6" &SEC = "1" #&CDS_SEC = "1";
"1":   PN = "1"  !CDS_PN = "1";
"2":   PN = "2"  !CDS_PN = "2";
BODY = "RESISTOR","I44": LOCATION = "R174" #&CDS_LOCATION = "R174" &SEC = "1" #&CDS_SEC = "1";
"1":   PN = "1"  !CDS_PN = "1";
"2":   PN = "2"  !CDS_PN = "2";
BODY = "RESISTOR","I45": LOCATION = "R166" #&CDS_LOCATION = "R166" &SEC = "1" #&CDS_SEC = "1";
"1":   PN = "1"  !CDS_PN = "1";
"2":   PN = "2"  !CDS_PN = "2";
BODY = "CAPACITOR","I46": LOCATION = "C187" #&CDS_LOCATION = "C187" &SEC = "1" #&CDS_SEC = "1";
"1":   PN = "1"  !CDS_PN = "1";
"2":   PN = "2"  !CDS_PN = "2";
BODY = "CAPACITOR","I47": LOCATION = "C186" #&CDS_LOCATION = "C186" &SEC = "1" #&CDS_SEC = "1";
"1":   PN = "1"  !CDS_PN = "1";
"2":   PN = "2"  !CDS_PN = "2";
BODY = "CAPACITOR","I49": LOCATION = "C191" #&CDS_LOCATION = "C191" &SEC = "1" #&CDS_SEC = "1";
"1":   PN = "1"  !CDS_PN = "1";
"2":   PN = "2"  !CDS_PN = "2";
BODY = "CAPACITOR","I51": LOCATION = "C189" #&CDS_LOCATION = "C189" &SEC = "1" #&CDS_SEC = "1";
"1":   PN = "1"  !CDS_PN = "1";
"2":   PN = "2"  !CDS_PN = "2";
BODY = "ISL80101IRAJZ_DFN10","I52": LOCATION = "U21" #&CDS_LOCATION = "U21" &SEC = "1" #&CDS_SEC = "1";
"ENABLE":   PN = "7"  !CDS_PN = "7";
"GND":   PN = "5"  !CDS_PN = "5";
"NC":   PN = "8"  !CDS_PN = "8";
"PG":   PN = "4"  !CDS_PN = "4";
"SENSE/ADJ":   PN = "3"  !CDS_PN = "3";
"SS":   PN = "6"  !CDS_PN = "6";
"THRM_PAD":   PN = "11"  !CDS_PN = "11";
"VIN_1":   PN = "9"  !CDS_PN = "9";
"VIN_2":   PN = "10"  !CDS_PN = "10";
"VOUT_1":   PN = "1"  !CDS_PN = "1";
"VOUT_2":   PN = "2"  !CDS_PN = "2";
BODY = "RESISTOR","I59": LOCATION = "R185" #&CDS_LOCATION = "R185" &SEC = "1" #&CDS_SEC = "1";
"1":   PN = "1"  !CDS_PN = "1";
"2":   PN = "2"  !CDS_PN = "2";
BODY = "CAPACITOR","I60": LOCATION = "C194" #&CDS_LOCATION = "C194" &SEC = "1" #&CDS_SEC = "1";
"1":   PN = "1"  !CDS_PN = "1";
"2":   PN = "2"  !CDS_PN = "2";
BODY = "CAPACITOR","I61": LOCATION = "C196" #&CDS_LOCATION = "C196" &SEC = "1" #&CDS_SEC = "1";
"1":   PN = "1"  !CDS_PN = "1";
"2":   PN = "2"  !CDS_PN = "2";
BODY = "CAPACITOR","I71": LOCATION = "C193" #&CDS_LOCATION = "C193" &SEC = "1" #&CDS_SEC = "1";
"1":   PN = "1"  !CDS_PN = "1";
"2":   PN = "2"  !CDS_PN = "2";
BODY = "RESISTOR","I73": LOCATION = "R179" #&CDS_LOCATION = "R179" &SEC = "1" #&CDS_SEC = "1";
"1":   PN = "1"  !CDS_PN = "1";
"2":   PN = "2"  !CDS_PN = "2";
BODY = "RESISTOR","I74": LOCATION = "R182" #&CDS_LOCATION = "R182" &SEC = "1" #&CDS_SEC = "1";
"1":   PN = "1"  !CDS_PN = "1";
"2":   PN = "2"  !CDS_PN = "2";
BODY = "RESISTOR","I78": LOCATION = "R187" #&CDS_LOCATION = "R187" &SEC = "1" #&CDS_SEC = "1";
"1":   PN = "1"  !CDS_PN = "1";
"2":   PN = "2"  !CDS_PN = "2";
BODY = "RESISTOR","I79": LOCATION = "R188" #&CDS_LOCATION = "R188" &SEC = "1" #&CDS_SEC = "1";
"1":   PN = "1"  !CDS_PN = "1";
"2":   PN = "2"  !CDS_PN = "2";
BODY = "RESISTOR","I80": LOCATION = "R190" #&CDS_LOCATION = "R190" &SEC = "1" #&CDS_SEC = "1";
"1":   PN = "1"  !CDS_PN = "1";
"2":   PN = "2"  !CDS_PN = "2";
BODY = "CAPACITOR","I81": LOCATION = "C195" #&CDS_LOCATION = "C195" &SEC = "1" #&CDS_SEC = "1";
"1":   PN = "1"  !CDS_PN = "1";
"2":   PN = "2"  !CDS_PN = "2";
BODY = "CAPACITOR","I83": LOCATION = "C197" #&CDS_LOCATION = "C197" &SEC = "1" #&CDS_SEC = "1";
"1":   PN = "1"  !CDS_PN = "1";
"2":   PN = "2"  !CDS_PN = "2";
BODY = "CAPACITOR","I93": LOCATION = "C180" #&CDS_LOCATION = "C180" &SEC = "1" #&CDS_SEC = "1";
"1":   PN = "1"  !CDS_PN = "1";
"2":   PN = "2"  !CDS_PN = "2";
BODY = "CAPACITOR","I94": LOCATION = "C182" #&CDS_LOCATION = "C182" &SEC = "1" #&CDS_SEC = "1";
"1":   PN = "1"  !CDS_PN = "1";
"2":   PN = "2"  !CDS_PN = "2";
BODY = "CAPACITOR","I97": LOCATION = "C181" #&CDS_LOCATION = "C181" &SEC = "1" #&CDS_SEC = "1";
"1":   PN = "1"  !CDS_PN = "1";
"2":   PN = "2"  !CDS_PN = "2";
BODY = "CAPACITOR","I98": LOCATION = "C183" #&CDS_LOCATION = "C183" &SEC = "1" #&CDS_SEC = "1";
"1":   PN = "1"  !CDS_PN = "1";
"2":   PN = "2"  !CDS_PN = "2";
DRAWING = "@timecard_lib.timecard(sch_1):page161";
BODY = "XC7A200T_2FBG484C_FBG484","I2": LOCATION = "U24" #&CDS_LOCATION = "U24" &SEC = "2" #&CDS_SEC = "2";
"IO_0_13":   PN = "Y17"  !CDS_PN = "Y17";
"IO_0_14":   PN = "P20"  !CDS_PN = "P20";
"IO_25_14":   PN = "N15"  !CDS_PN = "N15";
"IO_L1N_T0_13":   PN = "AA16"  !CDS_PN = "AA16";
"IO_L1N_T0_D01_DIN_14":   PN = "R22"  !CDS_PN = "R22";
"IO_L1P_T0_13":   PN = "Y16"  !CDS_PN = "Y16";
"IO_L1P_T0_D00_MOSI_14":   PN = "P22"  !CDS_PN = "P22";
"IO_L2N_T0_13":   PN = "AB17"  !CDS_PN = "AB17";
"IO_L2N_T0_D03_14":   PN = "R21"  !CDS_PN = "R21";
"IO_L2P_T0_13":   PN = "AB16"  !CDS_PN = "AB16";
"IO_L2P_T0_D02_14":   PN = "P21"  !CDS_PN = "P21";
"IO_L3N_T0_DQS_13":   PN = "AB13"  !CDS_PN = "AB13";
"IO_L3N_T0_DQS_EMCCLK_14":   PN = "V22"  !CDS_PN = "V22";
"IO_L3P_T0_DQS_13":   PN = "AA13"  !CDS_PN = "AA13";
"IO_L3P_T0_DQS_PUDC_14*":   PN = "U22"  !CDS_PN = "U22";
"IO_L4N_T0_13":   PN = "AB15"  !CDS_PN = "AB15";
"IO_L4N_T0_D05_14":   PN = "U21"  !CDS_PN = "U21";
"IO_L4P_T0_13":   PN = "AA15"  !CDS_PN = "AA15";
"IO_L4P_T0_D04_14":   PN = "T21"  !CDS_PN = "T21";
"IO_L5N_T0_13":   PN = "AA14"  !CDS_PN = "AA14";
"IO_L5N_T0_D07_14":   PN = "R19"  !CDS_PN = "R19";
"IO_L5P_T0_13":   PN = "Y13"  !CDS_PN = "Y13";
"IO_L5P_T0_D06_14":   PN = "P19"  !CDS_PN = "P19";
"IO_L6N_T0_D08_VREF_14":   PN = "T20"  !CDS_PN = "T20";
"IO_L6N_T0_VREF_13":   PN = "Y14"  !CDS_PN = "Y14";
"IO_L6P_T0_13":   PN = "W14"  !CDS_PN = "W14";
"IO_L6P_T0_FCS_B_14":   PN = "T19"  !CDS_PN = "T19";
"IO_L7N_T1_13":   PN = "AB12"  !CDS_PN = "AB12";
"IO_L7N_T1_D10_14":   PN = "W22"  !CDS_PN = "W22";
"IO_L7P_T1_13":   PN = "AB11"  !CDS_PN = "AB11";
"IO_L7P_T1_D09_14":   PN = "W21"  !CDS_PN = "W21";
"IO_L8N_T1_13":   PN = "AB10"  !CDS_PN = "AB10";
"IO_L8N_T1_D12_14":   PN = "AA21"  !CDS_PN = "AA21";
"IO_L8P_T1_13":   PN = "AA9"  !CDS_PN = "AA9";
"IO_L8P_T1_D11_14":   PN = "AA20"  !CDS_PN = "AA20";
"IO_L9N_T1_DQS_13":   PN = "AA11"  !CDS_PN = "AA11";
"IO_L9N_T1_DQS_D13_14":   PN = "Y22"  !CDS_PN = "Y22";
"IO_L9P_T1_DQS_13":   PN = "AA10"  !CDS_PN = "AA10";
"IO_L9P_T1_DQS_14":   PN = "Y21"  !CDS_PN = "Y21";
"IO_L10N_T1_13":   PN = "W10"  !CDS_PN = "W10";
"IO_L10N_T1_D15_14":   PN = "AB22"  !CDS_PN = "AB22";
"IO_L10P_T1_13":   PN = "V10"  !CDS_PN = "V10";
"IO_L10P_T1_D14_14":   PN = "AB21"  !CDS_PN = "AB21";
"IO_L11N_T1_SRCC_13":   PN = "Y12"  !CDS_PN = "Y12";
"IO_L11N_T1_SRCC_14":   PN = "V20"  !CDS_PN = "V20";
"IO_L11P_T1_SRCC_13":   PN = "Y11"  !CDS_PN = "Y11";
"IO_L11P_T1_SRCC_14":   PN = "U20"  !CDS_PN = "U20";
"IO_L12N_T1_MRCC_13":   PN = "W12"  !CDS_PN = "W12";
"IO_L12N_T1_MRCC_14":   PN = "W20"  !CDS_PN = "W20";
"IO_L12P_T1_MRCC_13":   PN = "W11"  !CDS_PN = "W11";
"IO_L12P_T1_MRCC_14":   PN = "W19"  !CDS_PN = "W19";
"IO_L13N_T2_MRCC_13":   PN = "V14"  !CDS_PN = "V14";
"IO_L13N_T2_MRCC_14":   PN = "Y19"  !CDS_PN = "Y19";
"IO_L13P_T2_MRCC_13":   PN = "V13"  !CDS_PN = "V13";
"IO_L13P_T2_MRCC_14":   PN = "Y18"  !CDS_PN = "Y18";
"IO_L14N_T2_SRCC_13":   PN = "V15"  !CDS_PN = "V15";
"IO_L14N_T2_SRCC_14":   PN = "V19"  !CDS_PN = "V19";
"IO_L14P_T2_SRCC_13":   PN = "U15"  !CDS_PN = "U15";
"IO_L14P_T2_SRCC_14":   PN = "V18"  !CDS_PN = "V18";
"IO_L15N_T2_DQS_13":   PN = "T15"  !CDS_PN = "T15";
"IO_L15N_T2_DQS_DOUT_CSO_14*":   PN = "AB20"  !CDS_PN = "AB20";
"IO_L15P_T2_DQS_13":   PN = "T14"  !CDS_PN = "T14";
"IO_L15P_T2_DQS_RDWR_14*":   PN = "AA19"  !CDS_PN = "AA19";
"IO_L16N_T2_13":   PN = "W16"  !CDS_PN = "W16";
"IO_L16N_T2_A15_D31_14":   PN = "W17"  !CDS_PN = "W17";
"IO_L16P_T2_13":   PN = "W15"  !CDS_PN = "W15";
"IO_L16P_T2_CSI_14*":   PN = "V17"  !CDS_PN = "V17";
"IO_L17N_T2_13":   PN = "U16"  !CDS_PN = "U16";
"IO_L17N_T2_A13_D29_14":   PN = "AB18"  !CDS_PN = "AB18";
"IO_L17P_T2_13":   PN = "T16"  !CDS_PN = "T16";
"IO_L17P_T2_A14_D30_14":   PN = "AA18"  !CDS_PN = "AA18";
"IO_L18N_T2_A11_D27_14":   PN = "U18"  !CDS_PN = "U18";
"IO_L18P_T2_A12_D28_14":   PN = "U17"  !CDS_PN = "U17";
"IO_L19N_T3_A09_D25_VREF_14":   PN = "R14"  !CDS_PN = "R14";
"IO_L19P_T3_A10_D26_14":   PN = "P14"  !CDS_PN = "P14";
"IO_L20N_T3_A07_D23_14":   PN = "T18"  !CDS_PN = "T18";
"IO_L20P_T3_A08_D24_14":   PN = "R18"  !CDS_PN = "R18";
"IO_L21N_T3_DQS_A06_D22_14":   PN = "P17"  !CDS_PN = "P17";
"IO_L21P_T3_DQS_14":   PN = "N17"  !CDS_PN = "N17";
"IO_L22N_T3_A04_D20_14":   PN = "R16"  !CDS_PN = "R16";
"IO_L22P_T3_A05_D21_14":   PN = "P15"  !CDS_PN = "P15";
"IO_L23N_T3_A02_D18_14":   PN = "N14"  !CDS_PN = "N14";
"IO_L23P_T3_A03_D19_14":   PN = "N13"  !CDS_PN = "N13";
"IO_L24N_T3_A00_D16_14":   PN = "R17"  !CDS_PN = "R17";
"IO_L24P_T3_A01_D17_14":   PN = "P16"  !CDS_PN = "P16";
BODY = "RESISTOR","I140": LOCATION = "R270" #&CDS_LOCATION = "R270" &SEC = "1" #&CDS_SEC = "1";
"1":   PN = "1"  !CDS_PN = "1";
"2":   PN = "2"  !CDS_PN = "2";
BODY = "RESISTOR","I200": #LOCATION = "R271" !CDS_LOCATION = "R271" &SEC = "1" #&CDS_SEC = "1";
"1":   PN = "1"  !CDS_PN = "1";
"2":   PN = "2"  !CDS_PN = "2";
BODY = "RESISTOR","I201": #LOCATION = "R288" !CDS_LOCATION = "R288" &SEC = "1" #&CDS_SEC = "1";
"1":   PN = "1"  !CDS_PN = "1";
"2":   PN = "2"  !CDS_PN = "2";
BODY = "RESISTOR","I239": LOCATION = "R437" #&CDS_LOCATION = "R437" &SEC = "1" #&CDS_SEC = "1";
"1":   PN = "1"  !CDS_PN = "1";
"2":   PN = "2"  !CDS_PN = "2";
BODY = "RESISTOR","I240": LOCATION = "R436" #&CDS_LOCATION = "R436" &SEC = "1" #&CDS_SEC = "1";
"1":   PN = "1"  !CDS_PN = "1";
"2":   PN = "2"  !CDS_PN = "2";
BODY = "RESISTOR","I241": LOCATION = "R501" #&CDS_LOCATION = "R501" &SEC = "1" #&CDS_SEC = "1";
"1":   PN = "1"  !CDS_PN = "1";
"2":   PN = "2"  !CDS_PN = "2";
BODY = "RESISTOR","I242": LOCATION = "R500" #&CDS_LOCATION = "R500" &SEC = "1" #&CDS_SEC = "1";
"1":   PN = "1"  !CDS_PN = "1";
"2":   PN = "2"  !CDS_PN = "2";
BODY = "RESISTOR","I244": LOCATION = "R504" #&CDS_LOCATION = "R504" &SEC = "1" #&CDS_SEC = "1";
"1":   PN = "1"  !CDS_PN = "1";
"2":   PN = "2"  !CDS_PN = "2";
BODY = "RESISTOR","I246": LOCATION = "R503" #&CDS_LOCATION = "R503" &SEC = "1" #&CDS_SEC = "1";
"1":   PN = "1"  !CDS_PN = "1";
"2":   PN = "2"  !CDS_PN = "2";
BODY = "RESISTOR","I247": LOCATION = "R502" #&CDS_LOCATION = "R502" &SEC = "1" #&CDS_SEC = "1";
"1":   PN = "1"  !CDS_PN = "1";
"2":   PN = "2"  !CDS_PN = "2";
BODY = "RESISTOR","I251": LOCATION = "R435" #&CDS_LOCATION = "R435" &SEC = "1" #&CDS_SEC = "1";
"1":   PN = "1"  !CDS_PN = "1";
"2":   PN = "2"  !CDS_PN = "2";
BODY = "RESISTOR","I252": LOCATION = "R223" #&CDS_LOCATION = "R223" &SEC = "1" #&CDS_SEC = "1";
"1":   PN = "1"  !CDS_PN = "1";
"2":   PN = "2"  !CDS_PN = "2";
BODY = "RESISTOR","I253": LOCATION = "R224" #&CDS_LOCATION = "R224" &SEC = "1" #&CDS_SEC = "1";
"1":   PN = "1"  !CDS_PN = "1";
"2":   PN = "2"  !CDS_PN = "2";
BODY = "RESISTOR","I258": LOCATION = "R234" #&CDS_LOCATION = "R234" &SEC = "1" #&CDS_SEC = "1";
"1":   PN = "1"  !CDS_PN = "1";
"2":   PN = "2"  !CDS_PN = "2";
BODY = "RESISTOR","I259": LOCATION = "R238" #&CDS_LOCATION = "R238" &SEC = "1" #&CDS_SEC = "1";
"1":   PN = "1"  !CDS_PN = "1";
"2":   PN = "2"  !CDS_PN = "2";
BODY = "RESISTOR","I260": LOCATION = "R348" #&CDS_LOCATION = "R348" &SEC = "1" #&CDS_SEC = "1";
"1":   PN = "1"  !CDS_PN = "1";
"2":   PN = "2"  !CDS_PN = "2";
BODY = "RESISTOR","I261": LOCATION = "R339" #&CDS_LOCATION = "R339" &SEC = "1" #&CDS_SEC = "1";
"1":   PN = "1"  !CDS_PN = "1";
"2":   PN = "2"  !CDS_PN = "2";
BODY = "RESISTOR","I263": LOCATION = "R362" #&CDS_LOCATION = "R362" &SEC = "1" #&CDS_SEC = "1";
"1":   PN = "1"  !CDS_PN = "1";
"2":   PN = "2"  !CDS_PN = "2";
DRAWING = "@timecard_lib.timecard(sch_1):page162";
BODY = "XC7A200T_2FBG484C_FBG484","I228": LOCATION = "U24" #&CDS_LOCATION = "U24" &SEC = "3" #&CDS_SEC = "3";
"IO_0_15":   PN = "J16"  !CDS_PN = "J16";
"IO_0_16":   PN = "F15"  !CDS_PN = "F15";
"IO_25_15":   PN = "M17"  !CDS_PN = "M17";
"IO_25_16":   PN = "F21"  !CDS_PN = "F21";
"IO_L1N_T0_16":   PN = "F14"  !CDS_PN = "F14";
"IO_L1N_T0_AD0N_15":   PN = "G13"  !CDS_PN = "G13";
"IO_L1P_T0_16":   PN = "F13"  !CDS_PN = "F13";
"IO_L1P_T0_AD0P_15":   PN = "H13"  !CDS_PN = "H13";
"IO_L2N_T0_16":   PN = "E17"  !CDS_PN = "E17";
"IO_L2N_T0_AD8N_15":   PN = "G16"  !CDS_PN = "G16";
"IO_L2P_T0_16":   PN = "F16"  !CDS_PN = "F16";
"IO_L2P_T0_AD8P_15":   PN = "G15"  !CDS_PN = "G15";
"IO_L3N_T0_DQS_16":   PN = "C15"  !CDS_PN = "C15";
"IO_L3N_T0_DQS_AD1N_15":   PN = "H14"  !CDS_PN = "H14";
"IO_L3P_T0_DQS_16":   PN = "C14"  !CDS_PN = "C14";
"IO_L3P_T0_DQS_AD1P_15":   PN = "J14"  !CDS_PN = "J14";
"IO_L4N_T0_15":   PN = "G18"  !CDS_PN = "G18";
"IO_L4N_T0_16":   PN = "E14"  !CDS_PN = "E14";
"IO_L4P_T0_15":   PN = "G17"  !CDS_PN = "G17";
"IO_L4P_T0_16":   PN = "E13"  !CDS_PN = "E13";
"IO_L5N_T0_16":   PN = "D16"  !CDS_PN = "D16";
"IO_L5N_T0_AD9N_15":   PN = "H15"  !CDS_PN = "H15";
"IO_L5P_T0_16":   PN = "E16"  !CDS_PN = "E16";
"IO_L5P_T0_AD9P_15":   PN = "J15"  !CDS_PN = "J15";
"IO_L6N_T0_VREF_15":   PN = "H18"  !CDS_PN = "H18";
"IO_L6N_T0_VREF_16":   PN = "D15"  !CDS_PN = "D15";
"IO_L6P_T0_15":   PN = "H17"  !CDS_PN = "H17";
"IO_L6P_T0_16":   PN = "D14"  !CDS_PN = "D14";
"IO_L7N_T1_16":   PN = "B16"  !CDS_PN = "B16";
"IO_L7N_T1_AD2N_15":   PN = "H22"  !CDS_PN = "H22";
"IO_L7P_T1_16":   PN = "B15"  !CDS_PN = "B15";
"IO_L7P_T1_AD2P_15":   PN = "J22"  !CDS_PN = "J22";
"IO_L8N_T1_16":   PN = "B13"  !CDS_PN = "B13";
"IO_L8N_T1_AD10N_15":   PN = "G20"  !CDS_PN = "G20";
"IO_L8P_T1_16":   PN = "C13"  !CDS_PN = "C13";
"IO_L8P_T1_AD10P_15":   PN = "H20"  !CDS_PN = "H20";
"IO_L9N_T1_DQS_16":   PN = "A16"  !CDS_PN = "A16";
"IO_L9N_T1_DQS_AD3N_15":   PN = "K22"  !CDS_PN = "K22";
"IO_L9P_T1_DQS_16":   PN = "A15"  !CDS_PN = "A15";
"IO_L9P_T1_DQS_AD3P_15":   PN = "K21"  !CDS_PN = "K21";
"IO_L10N_T1_16":   PN = "A14"  !CDS_PN = "A14";
"IO_L10N_T1_AD11N_15":   PN = "L21"  !CDS_PN = "L21";
"IO_L10P_T1_16":   PN = "A13"  !CDS_PN = "A13";
"IO_L10P_T1_AD11P_15":   PN = "M21"  !CDS_PN = "M21";
"IO_L11N_T1_SRCC_15":   PN = "J21"  !CDS_PN = "J21";
"IO_L11N_T1_SRCC_16":   PN = "B18"  !CDS_PN = "B18";
"IO_L11P_T1_SRCC_15":   PN = "J20"  !CDS_PN = "J20";
"IO_L11P_T1_SRCC_16":   PN = "B17"  !CDS_PN = "B17";
"IO_L12N_T1_MRCC_15":   PN = "H19"  !CDS_PN = "H19";
"IO_L12N_T1_MRCC_16":   PN = "C17"  !CDS_PN = "C17";
"IO_L12P_T1_MRCC_15":   PN = "J19"  !CDS_PN = "J19";
"IO_L12P_T1_MRCC_16":   PN = "D17"  !CDS_PN = "D17";
"IO_L13N_T2_MRCC_15":   PN = "K19"  !CDS_PN = "K19";
"IO_L13N_T2_MRCC_16":   PN = "C19"  !CDS_PN = "C19";
"IO_L13P_T2_MRCC_15":   PN = "K18"  !CDS_PN = "K18";
"IO_L13P_T2_MRCC_16":   PN = "C18"  !CDS_PN = "C18";
"IO_L14N_T2_SRCC_15":   PN = "L20"  !CDS_PN = "L20";
"IO_L14N_T2_SRCC_16":   PN = "D19"  !CDS_PN = "D19";
"IO_L14P_T2_SRCC_15":   PN = "L19"  !CDS_PN = "L19";
"IO_L14P_T2_SRCC_16":   PN = "E19"  !CDS_PN = "E19";
"IO_L15N_T2_DQS_16":   PN = "E18"  !CDS_PN = "E18";
"IO_L15N_T2_DQS_ADV_B_15":   PN = "M22"  !CDS_PN = "M22";
"IO_L15P_T2_DQS_15":   PN = "N22"  !CDS_PN = "N22";
"IO_L15P_T2_DQS_16":   PN = "F18"  !CDS_PN = "F18";
"IO_L16N_T2_16":   PN = "A20"  !CDS_PN = "A20";
"IO_L16N_T2_A27_15":   PN = "L18"  !CDS_PN = "L18";
"IO_L16P_T2_16":   PN = "B20"  !CDS_PN = "B20";
"IO_L16P_T2_A28_15":   PN = "M18"  !CDS_PN = "M18";
"IO_L17N_T2_16":   PN = "A19"  !CDS_PN = "A19";
"IO_L17N_T2_A25_15":   PN = "N19"  !CDS_PN = "N19";
"IO_L17P_T2_16":   PN = "A18"  !CDS_PN = "A18";
"IO_L17P_T2_A26_15":   PN = "N18"  !CDS_PN = "N18";
"IO_L18N_T2_16":   PN = "F20"  !CDS_PN = "F20";
"IO_L18N_T2_A23_15":   PN = "M20"  !CDS_PN = "M20";
"IO_L18P_T2_16":   PN = "F19"  !CDS_PN = "F19";
"IO_L18P_T2_A24_15":   PN = "N20"  !CDS_PN = "N20";
"IO_L19N_T3_A21_VREF_15":   PN = "K14"  !CDS_PN = "K14";
"IO_L19N_T3_VREF_16":   PN = "C20"  !CDS_PN = "C20";
"IO_L19P_T3_16":   PN = "D20"  !CDS_PN = "D20";
"IO_L19P_T3_A22_15":   PN = "K13"  !CDS_PN = "K13";
"IO_L20N_T3_16":   PN = "B22"  !CDS_PN = "B22";
"IO_L20N_T3_A19_15":   PN = "L13"  !CDS_PN = "L13";
"IO_L20P_T3_16":   PN = "C22"  !CDS_PN = "C22";
"IO_L20P_T3_A20_15":   PN = "M13"  !CDS_PN = "M13";
"IO_L21N_T3_DQS_16":   PN = "A21"  !CDS_PN = "A21";
"IO_L21N_T3_DQS_A18_15":   PN = "J17"  !CDS_PN = "J17";
"IO_L21P_T3_DQS_15":   PN = "K17"  !CDS_PN = "K17";
"IO_L21P_T3_DQS_16":   PN = "B21"  !CDS_PN = "B21";
"IO_L22N_T3_16":   PN = "D22"  !CDS_PN = "D22";
"IO_L22N_T3_A16_15":   PN = "L15"  !CDS_PN = "L15";
"IO_L22P_T3_16":   PN = "E22"  !CDS_PN = "E22";
"IO_L22P_T3_A17_15":   PN = "L14"  !CDS_PN = "L14";
"IO_L23N_T3_16":   PN = "D21"  !CDS_PN = "D21";
"IO_L23N_T3_FWE_B_15":   PN = "K16"  !CDS_PN = "K16";
"IO_L23P_T3_16":   PN = "E21"  !CDS_PN = "E21";
"IO_L23P_T3_FOE_B_15":   PN = "L16"  !CDS_PN = "L16";
"IO_L24N_T3_16":   PN = "G22"  !CDS_PN = "G22";
"IO_L24N_T3_RS0_15":   PN = "M16"  !CDS_PN = "M16";
"IO_L24P_T3_16":   PN = "G21"  !CDS_PN = "G21";
"IO_L24P_T3_RS1_15":   PN = "M15"  !CDS_PN = "M15";
DRAWING = "@timecard_lib.timecard(sch_1):page163";
BODY = "XC7A200T_2FBG484C_FBG484","I1": LOCATION = "U24" #&CDS_LOCATION = "U24" &SEC = "4" #&CDS_SEC = "4";
"IO_0_34":   PN = "T3"  !CDS_PN = "T3";
"IO_0_35":   PN = "F4"  !CDS_PN = "F4";
"IO_25_34":   PN = "U7"  !CDS_PN = "U7";
"IO_25_35":   PN = "L6"  !CDS_PN = "L6";
"IO_L1N_T0_34":   PN = "U1"  !CDS_PN = "U1";
"IO_L1N_T0_AD4N_35":   PN = "A1"  !CDS_PN = "A1";
"IO_L1P_T0_34":   PN = "T1"  !CDS_PN = "T1";
"IO_L1P_T0_AD4P_35":   PN = "B1"  !CDS_PN = "B1";
"IO_L2N_T0_34":   PN = "V2"  !CDS_PN = "V2";
"IO_L2N_T0_AD12N_35":   PN = "B2"  !CDS_PN = "B2";
"IO_L2P_T0_34":   PN = "U2"  !CDS_PN = "U2";
"IO_L2P_T0_AD12P_35":   PN = "C2"  !CDS_PN = "C2";
"IO_L3N_T0_DQS_34":   PN = "R2"  !CDS_PN = "R2";
"IO_L3N_T0_DQS_AD5N_35":   PN = "D1"  !CDS_PN = "D1";
"IO_L3P_T0_DQS_34":   PN = "R3"  !CDS_PN = "R3";
"IO_L3P_T0_DQS_AD5P_35":   PN = "E1"  !CDS_PN = "E1";
"IO_L4N_T0_34":   PN = "Y2"  !CDS_PN = "Y2";
"IO_L4N_T0_35":   PN = "D2"  !CDS_PN = "D2";
"IO_L4P_T0_34":   PN = "W2"  !CDS_PN = "W2";
"IO_L4P_T0_35":   PN = "E2"  !CDS_PN = "E2";
"IO_L5N_T0_34":   PN = "Y1"  !CDS_PN = "Y1";
"IO_L5N_T0_AD13N_35":   PN = "F1"  !CDS_PN = "F1";
"IO_L5P_T0_34":   PN = "W1"  !CDS_PN = "W1";
"IO_L5P_T0_AD13P_35":   PN = "G1"  !CDS_PN = "G1";
"IO_L6N_T0_VREF_34":   PN = "V3"  !CDS_PN = "V3";
"IO_L6N_T0_VREF_35":   PN = "E3"  !CDS_PN = "E3";
"IO_L6P_T0_34":   PN = "U3"  !CDS_PN = "U3";
"IO_L6P_T0_35":   PN = "F3"  !CDS_PN = "F3";
"IO_L7N_T1_34":   PN = "AB1"  !CDS_PN = "AB1";
"IO_L7N_T1_AD6N_35":   PN = "J1"  !CDS_PN = "J1";
"IO_L7P_T1_34":   PN = "AA1"  !CDS_PN = "AA1";
"IO_L7P_T1_AD6P_35":   PN = "K1"  !CDS_PN = "K1";
"IO_L8N_T1_34":   PN = "AB2"  !CDS_PN = "AB2";
"IO_L8N_T1_AD14N_35":   PN = "G2"  !CDS_PN = "G2";
"IO_L8P_T1_34":   PN = "AB3"  !CDS_PN = "AB3";
"IO_L8P_T1_AD14P_35":   PN = "H2"  !CDS_PN = "H2";
"IO_L9N_T1_DQS_34":   PN = "AA3"  !CDS_PN = "AA3";
"IO_L9N_T1_DQS_AD7N_35":   PN = "J2"  !CDS_PN = "J2";
"IO_L9P_T1_DQS_34":   PN = "Y3"  !CDS_PN = "Y3";
"IO_L9P_T1_DQS_AD7P_35":   PN = "K2"  !CDS_PN = "K2";
"IO_L10N_T1_34":   PN = "AB5"  !CDS_PN = "AB5";
"IO_L10N_T1_AD15N_35":   PN = "H5"  !CDS_PN = "H5";
"IO_L10P_T1_34":   PN = "AA5"  !CDS_PN = "AA5";
"IO_L10P_T1_AD15P_35":   PN = "J5"  !CDS_PN = "J5";
"IO_L11N_T1_SRCC_34":   PN = "AA4"  !CDS_PN = "AA4";
"IO_L11N_T1_SRCC_35":   PN = "G3"  !CDS_PN = "G3";
"IO_L11P_T1_SRCC_34":   PN = "Y4"  !CDS_PN = "Y4";
"IO_L11P_T1_SRCC_35":   PN = "H3"  !CDS_PN = "H3";
"IO_L12N_T1_MRCC_34":   PN = "W4"  !CDS_PN = "W4";
"IO_L12N_T1_MRCC_35":   PN = "G4"  !CDS_PN = "G4";
"IO_L12P_T1_MRCC_34":   PN = "V4"  !CDS_PN = "V4";
"IO_L12P_T1_MRCC_35":   PN = "H4"  !CDS_PN = "H4";
"IO_L13N_T2_MRCC_34":   PN = "T4"  !CDS_PN = "T4";
"IO_L13N_T2_MRCC_35":   PN = "J4"  !CDS_PN = "J4";
"IO_L13P_T2_MRCC_34":   PN = "R4"  !CDS_PN = "R4";
"IO_L13P_T2_MRCC_35":   PN = "K4"  !CDS_PN = "K4";
"IO_L14N_T2_SRCC_34":   PN = "U5"  !CDS_PN = "U5";
"IO_L14N_T2_SRCC_35":   PN = "K3"  !CDS_PN = "K3";
"IO_L14P_T2_SRCC_34":   PN = "T5"  !CDS_PN = "T5";
"IO_L14P_T2_SRCC_35":   PN = "L3"  !CDS_PN = "L3";
"IO_L15N_T2_DQS_34":   PN = "W5"  !CDS_PN = "W5";
"IO_L15N_T2_DQS_35":   PN = "L1"  !CDS_PN = "L1";
"IO_L15P_T2_DQS_34":   PN = "W6"  !CDS_PN = "W6";
"IO_L15P_T2_DQS_35":   PN = "M1"  !CDS_PN = "M1";
"IO_L16N_T2_34":   PN = "V5"  !CDS_PN = "V5";
"IO_L16N_T2_35":   PN = "M2"  !CDS_PN = "M2";
"IO_L16P_T2_34":   PN = "U6"  !CDS_PN = "U6";
"IO_L16P_T2_35":   PN = "M3"  !CDS_PN = "M3";
"IO_L17N_T2_34":   PN = "T6"  !CDS_PN = "T6";
"IO_L17N_T2_35":   PN = "J6"  !CDS_PN = "J6";
"IO_L17P_T2_34":   PN = "R6"  !CDS_PN = "R6";
"IO_L17P_T2_35":   PN = "K6"  !CDS_PN = "K6";
"IO_L18N_T2_34":   PN = "AA6"  !CDS_PN = "AA6";
"IO_L18N_T2_35":   PN = "L4"  !CDS_PN = "L4";
"IO_L18P_T2_34":   PN = "Y6"  !CDS_PN = "Y6";
"IO_L18P_T2_35":   PN = "L5"  !CDS_PN = "L5";
"IO_L19N_T3_VREF_34":   PN = "W7"  !CDS_PN = "W7";
"IO_L19N_T3_VREF_35":   PN = "N3"  !CDS_PN = "N3";
"IO_L19P_T3_34":   PN = "V7"  !CDS_PN = "V7";
"IO_L19P_T3_35":   PN = "N4"  !CDS_PN = "N4";
"IO_L20N_T3_34":   PN = "AB6"  !CDS_PN = "AB6";
"IO_L20N_T3_35":   PN = "P1"  !CDS_PN = "P1";
"IO_L20P_T3_34":   PN = "AB7"  !CDS_PN = "AB7";
"IO_L20P_T3_35":   PN = "R1"  !CDS_PN = "R1";
"IO_L21N_T3_DQS_34":   PN = "V8"  !CDS_PN = "V8";
"IO_L21N_T3_DQS_35":   PN = "P4"  !CDS_PN = "P4";
"IO_L21P_T3_DQS_34":   PN = "V9"  !CDS_PN = "V9";
"IO_L21P_T3_DQS_35":   PN = "P5"  !CDS_PN = "P5";
"IO_L22N_T3_34":   PN = "AB8"  !CDS_PN = "AB8";
"IO_L22N_T3_35":   PN = "N2"  !CDS_PN = "N2";
"IO_L22P_T3_34":   PN = "AA8"  !CDS_PN = "AA8";
"IO_L22P_T3_35":   PN = "P2"  !CDS_PN = "P2";
"IO_L23N_T3_34":   PN = "Y7"  !CDS_PN = "Y7";
"IO_L23N_T3_35":   PN = "M5"  !CDS_PN = "M5";
"IO_L23P_T3_34":   PN = "Y8"  !CDS_PN = "Y8";
"IO_L23P_T3_35":   PN = "M6"  !CDS_PN = "M6";
"IO_L24N_T3_34":   PN = "Y9"  !CDS_PN = "Y9";
"IO_L24N_T3_35":   PN = "N5"  !CDS_PN = "N5";
"IO_L24P_T3_34":   PN = "W9"  !CDS_PN = "W9";
"IO_L24P_T3_35":   PN = "P6"  !CDS_PN = "P6";
BODY = "RESISTOR","I36": LOCATION = "R278" #&CDS_LOCATION = "R278" &SEC = "1" #&CDS_SEC = "1";
"1":   PN = "1"  !CDS_PN = "1";
"2":   PN = "2"  !CDS_PN = "2";
BODY = "RESISTOR","I37": LOCATION = "R277" #&CDS_LOCATION = "R277" &SEC = "1" #&CDS_SEC = "1";
"1":   PN = "1"  !CDS_PN = "1";
"2":   PN = "2"  !CDS_PN = "2";
BODY = "RESISTOR","I38": LOCATION = "R276" #&CDS_LOCATION = "R276" &SEC = "1" #&CDS_SEC = "1";
"1":   PN = "1"  !CDS_PN = "1";
"2":   PN = "2"  !CDS_PN = "2";
BODY = "RESISTOR","I39": LOCATION = "R275" #&CDS_LOCATION = "R275" &SEC = "1" #&CDS_SEC = "1";
"1":   PN = "1"  !CDS_PN = "1";
"2":   PN = "2"  !CDS_PN = "2";
BODY = "RESISTOR","I120": LOCATION = "R355" #&CDS_LOCATION = "R355" &SEC = "1" #&CDS_SEC = "1";
"1":   PN = "1"  !CDS_PN = "1";
"2":   PN = "2"  !CDS_PN = "2";
BODY = "RESISTOR","I126": #LOCATION = "R358" !CDS_LOCATION = "R358" &SEC = "1" #&CDS_SEC = "1";
"1":   PN = "1"  !CDS_PN = "1";
"2":   PN = "2"  !CDS_PN = "2";
BODY = "RESISTOR","I127": #LOCATION = "R359" !CDS_LOCATION = "R359" &SEC = "1" #&CDS_SEC = "1";
"1":   PN = "1"  !CDS_PN = "1";
"2":   PN = "2"  !CDS_PN = "2";
BODY = "RESISTOR","I128": #LOCATION = "R360" !CDS_LOCATION = "R360" &SEC = "1" #&CDS_SEC = "1";
"1":   PN = "1"  !CDS_PN = "1";
"2":   PN = "2"  !CDS_PN = "2";
BODY = "RESISTOR","I132": LOCATION = "R438" #&CDS_LOCATION = "R438" &SEC = "1" #&CDS_SEC = "1";
"1":   PN = "1"  !CDS_PN = "1";
"2":   PN = "2"  !CDS_PN = "2";
BODY = "RESISTOR","I133": LOCATION = "R439" #&CDS_LOCATION = "R439" &SEC = "1" #&CDS_SEC = "1";
"1":   PN = "1"  !CDS_PN = "1";
"2":   PN = "2"  !CDS_PN = "2";
BODY = "RESISTOR","I134": LOCATION = "R441" #&CDS_LOCATION = "R441" &SEC = "1" #&CDS_SEC = "1";
"1":   PN = "1"  !CDS_PN = "1";
"2":   PN = "2"  !CDS_PN = "2";
BODY = "RESISTOR","I135": LOCATION = "R440" #&CDS_LOCATION = "R440" &SEC = "1" #&CDS_SEC = "1";
"1":   PN = "1"  !CDS_PN = "1";
"2":   PN = "2"  !CDS_PN = "2";
DRAWING = "@timecard_lib.timecard(sch_1):page164";
BODY = "FERRITEBEAD","I36": LOCATION = "L35" #&CDS_LOCATION = "L35" &SEC = "1" #&CDS_SEC = "1";
"1":   PN = "1"  !CDS_PN = "1";
"2":   PN = "2"  !CDS_PN = "2";
BODY = "FERRITEBEAD","I37": LOCATION = "L34" #&CDS_LOCATION = "L34" &SEC = "1" #&CDS_SEC = "1";
"1":   PN = "1"  !CDS_PN = "1";
"2":   PN = "2"  !CDS_PN = "2";
BODY = "FERRITEBEAD","I102": LOCATION = "L33" #&CDS_LOCATION = "L33" &SEC = "1" #&CDS_SEC = "1";
"1":   PN = "1"  !CDS_PN = "1";
"2":   PN = "2"  !CDS_PN = "2";
BODY = "XC7A200T_2FBG484C_FBG484","I138": LOCATION = "U24" #&CDS_LOCATION = "U24" &SEC = "5" #&CDS_SEC = "5";
"GND_1":   PN = "A11"  !CDS_PN = "A11";
"GND_2":   PN = "A12"  !CDS_PN = "A12";
"GND_3":   PN = "A2"  !CDS_PN = "A2";
"GND_4":   PN = "A22"  !CDS_PN = "A22";
"GND_5":   PN = "A3"  !CDS_PN = "A3";
"GND_6":   PN = "A5"  !CDS_PN = "A5";
"GND_7":   PN = "A7"  !CDS_PN = "A7";
"GND_8":   PN = "A9"  !CDS_PN = "A9";
"GND_9":   PN = "AA12"  !CDS_PN = "AA12";
"GND_10":   PN = "AA2"  !CDS_PN = "AA2";
"GND_11":   PN = "AA22"  !CDS_PN = "AA22";
"GND_12":   PN = "AB19"  !CDS_PN = "AB19";
"GND_13":   PN = "AB9"  !CDS_PN = "AB9";
"GND_14":   PN = "B12"  !CDS_PN = "B12";
"GND_15":   PN = "B19"  !CDS_PN = "B19";
"GND_16":   PN = "B3"  !CDS_PN = "B3";
"GND_17":   PN = "C10"  !CDS_PN = "C10";
"GND_18":   PN = "C12"  !CDS_PN = "C12";
"GND_19":   PN = "C16"  !CDS_PN = "C16";
"GND_20":   PN = "C3"  !CDS_PN = "C3";
"GND_21":   PN = "C6"  !CDS_PN = "C6";
"GND_22":   PN = "D12"  !CDS_PN = "D12";
"GND_23":   PN = "D13"  !CDS_PN = "D13";
"GND_24":   PN = "D3"  !CDS_PN = "D3";
"GND_25":   PN = "D4"  !CDS_PN = "D4";
"GND_26":   PN = "D8"  !CDS_PN = "D8";
"GND_27":   PN = "E11"  !CDS_PN = "E11";
"GND_28":   PN = "E20"  !CDS_PN = "E20";
"GND_29":   PN = "E4"  !CDS_PN = "E4";
"GND_30":   PN = "E5"  !CDS_PN = "E5";
"GND_31":   PN = "E7"  !CDS_PN = "E7";
"GND_32":   PN = "E9"  !CDS_PN = "E9";
"GND_33":   PN = "F11"  !CDS_PN = "F11";
"GND_34":   PN = "F17"  !CDS_PN = "F17";
"GND_35":   PN = "F5"  !CDS_PN = "F5";
"GND_36":   PN = "G10"  !CDS_PN = "G10";
"GND_37":   PN = "G12"  !CDS_PN = "G12";
"GND_38":   PN = "G14"  !CDS_PN = "G14";
"GND_39":   PN = "G5"  !CDS_PN = "G5";
"GND_40":   PN = "G6"  !CDS_PN = "G6";
"GND_41":   PN = "G7"  !CDS_PN = "G7";
"GND_42":   PN = "G8"  !CDS_PN = "G8";
"GND_43":   PN = "G9"  !CDS_PN = "G9";
"GND_44":   PN = "H1"  !CDS_PN = "H1";
"GND_45":   PN = "H11"  !CDS_PN = "H11";
"GND_46":   PN = "H21"  !CDS_PN = "H21";
"GND_47":   PN = "H7"  !CDS_PN = "H7";
"GND_48":   PN = "H9"  !CDS_PN = "H9";
"GND_49":   PN = "J10"  !CDS_PN = "J10";
"GND_50":   PN = "J12"  !CDS_PN = "J12";
"GND_51":   PN = "J18"  !CDS_PN = "J18";
"GND_52":   PN = "J8"  !CDS_PN = "J8";
"GND_53":   PN = "K11"  !CDS_PN = "K11";
"GND_54":   PN = "K15"  !CDS_PN = "K15";
"GND_55":   PN = "K5"  !CDS_PN = "K5";
"GND_56":   PN = "K7"  !CDS_PN = "K7";
"GND_57":   PN = "L2"  !CDS_PN = "L2";
"GND_58":   PN = "L22"  !CDS_PN = "L22";
"GND_59":   PN = "L8"  !CDS_PN = "L8";
"GND_60":   PN = "M11"  !CDS_PN = "M11";
"GND_61":   PN = "M19"  !CDS_PN = "M19";
"GND_62":   PN = "M7"  !CDS_PN = "M7";
"GND_63":   PN = "N16"  !CDS_PN = "N16";
"GND_64":   PN = "N6"  !CDS_PN = "N6";
"GND_65":   PN = "N8"  !CDS_PN = "N8";
"GND_66":   PN = "P11"  !CDS_PN = "P11";
"GND_67":   PN = "P13"  !CDS_PN = "P13";
"GND_68":   PN = "P3"  !CDS_PN = "P3";
"GND_69":   PN = "P7"  !CDS_PN = "P7";
"GND_70":   PN = "P9"  !CDS_PN = "P9";
"GND_71":   PN = "R10"  !CDS_PN = "R10";
"GND_72":   PN = "R12"  !CDS_PN = "R12";
"GND_73":   PN = "R20"  !CDS_PN = "R20";
"GND_74":   PN = "R8"  !CDS_PN = "R8";
"GND_75":   PN = "T11"  !CDS_PN = "T11";
"GND_76":   PN = "T17"  !CDS_PN = "T17";
"GND_77":   PN = "T7"  !CDS_PN = "T7";
"GND_78":   PN = "T9"  !CDS_PN = "T9";
"GND_79":   PN = "U14"  !CDS_PN = "U14";
"GND_80":   PN = "U4"  !CDS_PN = "U4";
"GND_81":   PN = "V1"  !CDS_PN = "V1";
"GND_82":   PN = "V11"  !CDS_PN = "V11";
"GND_83":   PN = "V21"  !CDS_PN = "V21";
"GND_84":   PN = "W18"  !CDS_PN = "W18";
"GND_85":   PN = "W8"  !CDS_PN = "W8";
"GND_86":   PN = "Y15"  !CDS_PN = "Y15";
"GND_87":   PN = "Y5"  !CDS_PN = "Y5";
"GNDADC_0":   PN = "K9"  !CDS_PN = "K9";
"MGTAVCC_1":   PN = "D10"  !CDS_PN = "D10";
"MGTAVCC_2":   PN = "D6"  !CDS_PN = "D6";
"MGTAVCC_3":   PN = "E8"  !CDS_PN = "E8";
"MGTAVCC_4":   PN = "F7"  !CDS_PN = "F7";
"MGTAVCC_5":   PN = "F9"  !CDS_PN = "F9";
"MGTAVTT_1":   PN = "B11"  !CDS_PN = "B11";
"MGTAVTT_2":   PN = "B5"  !CDS_PN = "B5";
"MGTAVTT_3":   PN = "B7"  !CDS_PN = "B7";
"MGTAVTT_4":   PN = "B9"  !CDS_PN = "B9";
"MGTAVTT_5":   PN = "C4"  !CDS_PN = "C4";
"MGTAVTT_6":   PN = "C8"  !CDS_PN = "C8";
"VCCADC_0":   PN = "K10"  !CDS_PN = "K10";
"VCCAUX_1":   PN = "H12"  !CDS_PN = "H12";
"VCCAUX_2":   PN = "K12"  !CDS_PN = "K12";
"VCCAUX_3":   PN = "M12"  !CDS_PN = "M12";
"VCCAUX_4":   PN = "P12"  !CDS_PN = "P12";
"VCCAUX_5":   PN = "R11"  !CDS_PN = "R11";
"VCCBATT_0":   PN = "E12"  !CDS_PN = "E12";
"VCCBRAM_1":   PN = "J11"  !CDS_PN = "J11";
"VCCBRAM_2":   PN = "L11"  !CDS_PN = "L11";
"VCCBRAM_3":   PN = "N11"  !CDS_PN = "N11";
"VCCINT_1":   PN = "H10"  !CDS_PN = "H10";
"VCCINT_2":   PN = "H8"  !CDS_PN = "H8";
"VCCINT_3":   PN = "J7"  !CDS_PN = "J7";
"VCCINT_4":   PN = "J9"  !CDS_PN = "J9";
"VCCINT_5":   PN = "K8"  !CDS_PN = "K8";
"VCCINT_6":   PN = "L7"  !CDS_PN = "L7";
"VCCINT_7":   PN = "M8"  !CDS_PN = "M8";
"VCCINT_8":   PN = "N7"  !CDS_PN = "N7";
"VCCINT_9":   PN = "P10"  !CDS_PN = "P10";
"VCCINT_10":   PN = "P8"  !CDS_PN = "P8";
"VCCINT_11":   PN = "R7"  !CDS_PN = "R7";
"VCCINT_12":   PN = "R9"  !CDS_PN = "R9";
"VCCINT_13":   PN = "T10"  !CDS_PN = "T10";
"VCCINT_14":   PN = "T8"  !CDS_PN = "T8";
"VCCO_0_1":   PN = "F12"  !CDS_PN = "F12";
"VCCO_0_2":   PN = "T12"  !CDS_PN = "T12";
"VCCO_13_1":   PN = "AA17"  !CDS_PN = "AA17";
"VCCO_13_2":   PN = "AB14"  !CDS_PN = "AB14";
"VCCO_13_3":   PN = "V16"  !CDS_PN = "V16";
"VCCO_13_4":   PN = "W13"  !CDS_PN = "W13";
"VCCO_13_5":   PN = "Y10"  !CDS_PN = "Y10";
"VCCO_14_1":   PN = "M14"  !CDS_PN = "M14";
"VCCO_14_2":   PN = "P18"  !CDS_PN = "P18";
"VCCO_14_3":   PN = "R15"  !CDS_PN = "R15";
"VCCO_14_4":   PN = "T22"  !CDS_PN = "T22";
"VCCO_14_5":   PN = "U19"  !CDS_PN = "U19";
"VCCO_14_6":   PN = "Y20"  !CDS_PN = "Y20";
"VCCO_15_1":   PN = "G19"  !CDS_PN = "G19";
"VCCO_15_2":   PN = "H16"  !CDS_PN = "H16";
"VCCO_15_3":   PN = "J13"  !CDS_PN = "J13";
"VCCO_15_4":   PN = "K20"  !CDS_PN = "K20";
"VCCO_15_5":   PN = "L17"  !CDS_PN = "L17";
"VCCO_15_6":   PN = "N21"  !CDS_PN = "N21";
"VCCO_16_1":   PN = "A17"  !CDS_PN = "A17";
"VCCO_16_2":   PN = "B14"  !CDS_PN = "B14";
"VCCO_16_3":   PN = "C21"  !CDS_PN = "C21";
"VCCO_16_4":   PN = "D18"  !CDS_PN = "D18";
"VCCO_16_5":   PN = "E15"  !CDS_PN = "E15";
"VCCO_16_6":   PN = "F22"  !CDS_PN = "F22";
"VCCO_34_1":   PN = "AA7"  !CDS_PN = "AA7";
"VCCO_34_2":   PN = "AB4"  !CDS_PN = "AB4";
"VCCO_34_3":   PN = "R5"  !CDS_PN = "R5";
"VCCO_34_4":   PN = "T2"  !CDS_PN = "T2";
"VCCO_34_5":   PN = "V6"  !CDS_PN = "V6";
"VCCO_34_6":   PN = "W3"  !CDS_PN = "W3";
"VCCO_35_1":   PN = "C1"  !CDS_PN = "C1";
"VCCO_35_2":   PN = "F2"  !CDS_PN = "F2";
"VCCO_35_3":   PN = "H6"  !CDS_PN = "H6";
"VCCO_35_4":   PN = "J3"  !CDS_PN = "J3";
"VCCO_35_5":   PN = "M4"  !CDS_PN = "M4";
"VCCO_35_6":   PN = "N1"  !CDS_PN = "N1";
BODY = "FERRITEBEAD","I139": LOCATION = "L12" #&CDS_LOCATION = "L12" &SEC = "1" #&CDS_SEC = "1";
"1":   PN = "1"  !CDS_PN = "1";
"2":   PN = "2"  !CDS_PN = "2";
BODY = "CAPACITOR","I172": LOCATION = "C176" #&CDS_LOCATION = "C176" &SEC = "1" #&CDS_SEC = "1";
"1":   PN = "1"  !CDS_PN = "1";
"2":   PN = "2"  !CDS_PN = "2";
BODY = "CAPACITOR","I173": LOCATION = "C175" #&CDS_LOCATION = "C175" &SEC = "1" #&CDS_SEC = "1";
"1":   PN = "1"  !CDS_PN = "1";
"2":   PN = "2"  !CDS_PN = "2";
BODY = "CAPACITOR","I174": LOCATION = "C172" #&CDS_LOCATION = "C172" &SEC = "1" #&CDS_SEC = "1";
"1":   PN = "1"  !CDS_PN = "1";
"2":   PN = "2"  !CDS_PN = "2";
BODY = "CAPACITOR","I176": LOCATION = "C158" #&CDS_LOCATION = "C158" &SEC = "1" #&CDS_SEC = "1";
"1":   PN = "1"  !CDS_PN = "1";
"2":   PN = "2"  !CDS_PN = "2";
BODY = "CAPACITOR","I177": LOCATION = "C120" #&CDS_LOCATION = "C120" &SEC = "1" #&CDS_SEC = "1";
"1":   PN = "1"  !CDS_PN = "1";
"2":   PN = "2"  !CDS_PN = "2";
BODY = "CAPACITOR","I178": LOCATION = "C174" #&CDS_LOCATION = "C174" &SEC = "1" #&CDS_SEC = "1";
"1":   PN = "1"  !CDS_PN = "1";
"2":   PN = "2"  !CDS_PN = "2";
BODY = "CAPACITOR","I182": LOCATION = "C201" #&CDS_LOCATION = "C201" &SEC = "1" #&CDS_SEC = "1";
"1":   PN = "1"  !CDS_PN = "1";
"2":   PN = "2"  !CDS_PN = "2";
BODY = "CAPACITOR","I183": LOCATION = "C207" #&CDS_LOCATION = "C207" &SEC = "1" #&CDS_SEC = "1";
"1":   PN = "1"  !CDS_PN = "1";
"2":   PN = "2"  !CDS_PN = "2";
BODY = "CAPACITOR","I184": LOCATION = "C214" #&CDS_LOCATION = "C214" &SEC = "1" #&CDS_SEC = "1";
"1":   PN = "1"  !CDS_PN = "1";
"2":   PN = "2"  !CDS_PN = "2";
BODY = "CAPACITOR","I185": LOCATION = "C222" #&CDS_LOCATION = "C222" &SEC = "1" #&CDS_SEC = "1";
"1":   PN = "1"  !CDS_PN = "1";
"2":   PN = "2"  !CDS_PN = "2";
BODY = "CAPACITOR","I186": LOCATION = "C109" #&CDS_LOCATION = "C109" &SEC = "1" #&CDS_SEC = "1";
"1":   PN = "1"  !CDS_PN = "1";
"2":   PN = "2"  !CDS_PN = "2";
BODY = "CAPACITOR","I187": LOCATION = "C114" #&CDS_LOCATION = "C114" &SEC = "1" #&CDS_SEC = "1";
"1":   PN = "1"  !CDS_PN = "1";
"2":   PN = "2"  !CDS_PN = "2";
BODY = "CAPACITOR","I188": LOCATION = "C121" #&CDS_LOCATION = "C121" &SEC = "1" #&CDS_SEC = "1";
"1":   PN = "1"  !CDS_PN = "1";
"2":   PN = "2"  !CDS_PN = "2";
BODY = "CAPACITOR","I189": LOCATION = "C129" #&CDS_LOCATION = "C129" &SEC = "1" #&CDS_SEC = "1";
"1":   PN = "1"  !CDS_PN = "1";
"2":   PN = "2"  !CDS_PN = "2";
BODY = "CAPACITOR","I190": LOCATION = "C133" #&CDS_LOCATION = "C133" &SEC = "1" #&CDS_SEC = "1";
"1":   PN = "1"  !CDS_PN = "1";
"2":   PN = "2"  !CDS_PN = "2";
BODY = "CAPACITOR","I191": LOCATION = "C141" #&CDS_LOCATION = "C141" &SEC = "1" #&CDS_SEC = "1";
"1":   PN = "1"  !CDS_PN = "1";
"2":   PN = "2"  !CDS_PN = "2";
BODY = "CAPACITOR","I192": LOCATION = "C147" #&CDS_LOCATION = "C147" &SEC = "1" #&CDS_SEC = "1";
"1":   PN = "1"  !CDS_PN = "1";
"2":   PN = "2"  !CDS_PN = "2";
BODY = "CAPACITOR","I193": LOCATION = "C152" #&CDS_LOCATION = "C152" &SEC = "1" #&CDS_SEC = "1";
"1":   PN = "1"  !CDS_PN = "1";
"2":   PN = "2"  !CDS_PN = "2";
BODY = "CAPACITOR","I194": LOCATION = "C156" #&CDS_LOCATION = "C156" &SEC = "1" #&CDS_SEC = "1";
"1":   PN = "1"  !CDS_PN = "1";
"2":   PN = "2"  !CDS_PN = "2";
BODY = "CAPACITOR","I195": LOCATION = "C161" #&CDS_LOCATION = "C161" &SEC = "1" #&CDS_SEC = "1";
"1":   PN = "1"  !CDS_PN = "1";
"2":   PN = "2"  !CDS_PN = "2";
BODY = "CAPACITOR","I196": LOCATION = "C166" #&CDS_LOCATION = "C166" &SEC = "1" #&CDS_SEC = "1";
"1":   PN = "1"  !CDS_PN = "1";
"2":   PN = "2"  !CDS_PN = "2";
BODY = "CAPACITOR","I197": LOCATION = "C169" #&CDS_LOCATION = "C169" &SEC = "1" #&CDS_SEC = "1";
"1":   PN = "1"  !CDS_PN = "1";
"2":   PN = "2"  !CDS_PN = "2";
BODY = "CAPACITOR","I198": LOCATION = "C171" #&CDS_LOCATION = "C171" &SEC = "1" #&CDS_SEC = "1";
"1":   PN = "1"  !CDS_PN = "1";
"2":   PN = "2"  !CDS_PN = "2";
BODY = "CAPACITOR","I199": LOCATION = "C200" #&CDS_LOCATION = "C200" &SEC = "1" #&CDS_SEC = "1";
"1":   PN = "1"  !CDS_PN = "1";
"2":   PN = "2"  !CDS_PN = "2";
BODY = "CAPACITOR","I200": LOCATION = "C206" #&CDS_LOCATION = "C206" &SEC = "1" #&CDS_SEC = "1";
"1":   PN = "1"  !CDS_PN = "1";
"2":   PN = "2"  !CDS_PN = "2";
BODY = "CAPACITOR","I201": LOCATION = "C212" #&CDS_LOCATION = "C212" &SEC = "1" #&CDS_SEC = "1";
"1":   PN = "1"  !CDS_PN = "1";
"2":   PN = "2"  !CDS_PN = "2";
BODY = "CAPACITOR","I202": LOCATION = "C219" #&CDS_LOCATION = "C219" &SEC = "1" #&CDS_SEC = "1";
"1":   PN = "1"  !CDS_PN = "1";
"2":   PN = "2"  !CDS_PN = "2";
BODY = "CAPACITOR","I203": LOCATION = "C106" #&CDS_LOCATION = "C106" &SEC = "1" #&CDS_SEC = "1";
"1":   PN = "1"  !CDS_PN = "1";
"2":   PN = "2"  !CDS_PN = "2";
BODY = "CAPACITOR","I204": LOCATION = "C113" #&CDS_LOCATION = "C113" &SEC = "1" #&CDS_SEC = "1";
"1":   PN = "1"  !CDS_PN = "1";
"2":   PN = "2"  !CDS_PN = "2";
BODY = "CAPACITOR","I205": LOCATION = "C202" #&CDS_LOCATION = "C202" &SEC = "1" #&CDS_SEC = "1";
"1":   PN = "1"  !CDS_PN = "1";
"2":   PN = "2"  !CDS_PN = "2";
BODY = "CAPACITOR","I206": LOCATION = "C210" #&CDS_LOCATION = "C210" &SEC = "1" #&CDS_SEC = "1";
"1":   PN = "1"  !CDS_PN = "1";
"2":   PN = "2"  !CDS_PN = "2";
BODY = "CAPACITOR","I207": LOCATION = "C215" #&CDS_LOCATION = "C215" &SEC = "1" #&CDS_SEC = "1";
"1":   PN = "1"  !CDS_PN = "1";
"2":   PN = "2"  !CDS_PN = "2";
BODY = "CAPACITOR","I208": LOCATION = "C103" #&CDS_LOCATION = "C103" &SEC = "1" #&CDS_SEC = "1";
"1":   PN = "1"  !CDS_PN = "1";
"2":   PN = "2"  !CDS_PN = "2";
BODY = "CAPACITOR","I209": LOCATION = "C112" #&CDS_LOCATION = "C112" &SEC = "1" #&CDS_SEC = "1";
"1":   PN = "1"  !CDS_PN = "1";
"2":   PN = "2"  !CDS_PN = "2";
BODY = "CAPACITOR","I210": LOCATION = "C119" #&CDS_LOCATION = "C119" &SEC = "1" #&CDS_SEC = "1";
"1":   PN = "1"  !CDS_PN = "1";
"2":   PN = "2"  !CDS_PN = "2";
BODY = "CAPACITOR","I211": LOCATION = "C126" #&CDS_LOCATION = "C126" &SEC = "1" #&CDS_SEC = "1";
"1":   PN = "1"  !CDS_PN = "1";
"2":   PN = "2"  !CDS_PN = "2";
BODY = "CAPACITOR","I212": LOCATION = "C132" #&CDS_LOCATION = "C132" &SEC = "1" #&CDS_SEC = "1";
"1":   PN = "1"  !CDS_PN = "1";
"2":   PN = "2"  !CDS_PN = "2";
BODY = "CAPACITOR","I213": LOCATION = "C139" #&CDS_LOCATION = "C139" &SEC = "1" #&CDS_SEC = "1";
"1":   PN = "1"  !CDS_PN = "1";
"2":   PN = "2"  !CDS_PN = "2";
BODY = "CAPACITOR","I214": LOCATION = "C144" #&CDS_LOCATION = "C144" &SEC = "1" #&CDS_SEC = "1";
"1":   PN = "1"  !CDS_PN = "1";
"2":   PN = "2"  !CDS_PN = "2";
BODY = "CAPACITOR","I215": LOCATION = "C149" #&CDS_LOCATION = "C149" &SEC = "1" #&CDS_SEC = "1";
"1":   PN = "1"  !CDS_PN = "1";
"2":   PN = "2"  !CDS_PN = "2";
BODY = "CAPACITOR","I216": LOCATION = "C203" #&CDS_LOCATION = "C203" &SEC = "1" #&CDS_SEC = "1";
"1":   PN = "1"  !CDS_PN = "1";
"2":   PN = "2"  !CDS_PN = "2";
BODY = "CAPACITOR","I217": LOCATION = "C211" #&CDS_LOCATION = "C211" &SEC = "1" #&CDS_SEC = "1";
"1":   PN = "1"  !CDS_PN = "1";
"2":   PN = "2"  !CDS_PN = "2";
BODY = "CAPACITOR","I218": LOCATION = "C216" #&CDS_LOCATION = "C216" &SEC = "1" #&CDS_SEC = "1";
"1":   PN = "1"  !CDS_PN = "1";
"2":   PN = "2"  !CDS_PN = "2";
BODY = "CAPACITOR","I219": LOCATION = "C221" #&CDS_LOCATION = "C221" &SEC = "1" #&CDS_SEC = "1";
"1":   PN = "1"  !CDS_PN = "1";
"2":   PN = "2"  !CDS_PN = "2";
BODY = "CAPACITOR","I220": LOCATION = "C107" #&CDS_LOCATION = "C107" &SEC = "1" #&CDS_SEC = "1";
"1":   PN = "1"  !CDS_PN = "1";
"2":   PN = "2"  !CDS_PN = "2";
BODY = "CAPACITOR","I221": LOCATION = "C115" #&CDS_LOCATION = "C115" &SEC = "1" #&CDS_SEC = "1";
"1":   PN = "1"  !CDS_PN = "1";
"2":   PN = "2"  !CDS_PN = "2";
BODY = "CAPACITOR","I222": LOCATION = "C223" #&CDS_LOCATION = "C223" &SEC = "1" #&CDS_SEC = "1";
"1":   PN = "1"  !CDS_PN = "1";
"2":   PN = "2"  !CDS_PN = "2";
BODY = "CAPACITOR","I223": LOCATION = "C130" #&CDS_LOCATION = "C130" &SEC = "1" #&CDS_SEC = "1";
"1":   PN = "1"  !CDS_PN = "1";
"2":   PN = "2"  !CDS_PN = "2";
BODY = "CAPACITOR","I224": LOCATION = "C134" #&CDS_LOCATION = "C134" &SEC = "1" #&CDS_SEC = "1";
"1":   PN = "1"  !CDS_PN = "1";
"2":   PN = "2"  !CDS_PN = "2";
BODY = "CAPACITOR","I225": LOCATION = "C140" #&CDS_LOCATION = "C140" &SEC = "1" #&CDS_SEC = "1";
"1":   PN = "1"  !CDS_PN = "1";
"2":   PN = "2"  !CDS_PN = "2";
BODY = "CAPACITOR","I226": LOCATION = "C145" #&CDS_LOCATION = "C145" &SEC = "1" #&CDS_SEC = "1";
"1":   PN = "1"  !CDS_PN = "1";
"2":   PN = "2"  !CDS_PN = "2";
BODY = "CAPACITOR","I227": LOCATION = "C153" #&CDS_LOCATION = "C153" &SEC = "1" #&CDS_SEC = "1";
"1":   PN = "1"  !CDS_PN = "1";
"2":   PN = "2"  !CDS_PN = "2";
BODY = "CAPACITOR","I228": LOCATION = "C157" #&CDS_LOCATION = "C157" &SEC = "1" #&CDS_SEC = "1";
"1":   PN = "1"  !CDS_PN = "1";
"2":   PN = "2"  !CDS_PN = "2";
BODY = "CAPACITOR","I229": LOCATION = "C162" #&CDS_LOCATION = "C162" &SEC = "1" #&CDS_SEC = "1";
"1":   PN = "1"  !CDS_PN = "1";
"2":   PN = "2"  !CDS_PN = "2";
BODY = "CAPACITOR","I230": LOCATION = "C165" #&CDS_LOCATION = "C165" &SEC = "1" #&CDS_SEC = "1";
"1":   PN = "1"  !CDS_PN = "1";
"2":   PN = "2"  !CDS_PN = "2";
BODY = "CAPACITOR","I231": LOCATION = "C204" #&CDS_LOCATION = "C204" &SEC = "1" #&CDS_SEC = "1";
"1":   PN = "1"  !CDS_PN = "1";
"2":   PN = "2"  !CDS_PN = "2";
BODY = "CAPACITOR","I232": LOCATION = "C208" #&CDS_LOCATION = "C208" &SEC = "1" #&CDS_SEC = "1";
"1":   PN = "1"  !CDS_PN = "1";
"2":   PN = "2"  !CDS_PN = "2";
BODY = "CAPACITOR","I233": LOCATION = "C213" #&CDS_LOCATION = "C213" &SEC = "1" #&CDS_SEC = "1";
"1":   PN = "1"  !CDS_PN = "1";
"2":   PN = "2"  !CDS_PN = "2";
BODY = "CAPACITOR","I234": LOCATION = "C220" #&CDS_LOCATION = "C220" &SEC = "1" #&CDS_SEC = "1";
"1":   PN = "1"  !CDS_PN = "1";
"2":   PN = "2"  !CDS_PN = "2";
BODY = "CAPACITOR","I235": LOCATION = "C108" #&CDS_LOCATION = "C108" &SEC = "1" #&CDS_SEC = "1";
"1":   PN = "1"  !CDS_PN = "1";
"2":   PN = "2"  !CDS_PN = "2";
BODY = "CAPACITOR","I236": LOCATION = "C116" #&CDS_LOCATION = "C116" &SEC = "1" #&CDS_SEC = "1";
"1":   PN = "1"  !CDS_PN = "1";
"2":   PN = "2"  !CDS_PN = "2";
BODY = "CAPACITOR","I237": LOCATION = "C122" #&CDS_LOCATION = "C122" &SEC = "1" #&CDS_SEC = "1";
"1":   PN = "1"  !CDS_PN = "1";
"2":   PN = "2"  !CDS_PN = "2";
BODY = "CAPACITOR","I238": LOCATION = "C127" #&CDS_LOCATION = "C127" &SEC = "1" #&CDS_SEC = "1";
"1":   PN = "1"  !CDS_PN = "1";
"2":   PN = "2"  !CDS_PN = "2";
BODY = "CAPACITOR","I239": LOCATION = "C135" #&CDS_LOCATION = "C135" &SEC = "1" #&CDS_SEC = "1";
"1":   PN = "1"  !CDS_PN = "1";
"2":   PN = "2"  !CDS_PN = "2";
BODY = "CAPACITOR","I240": LOCATION = "C142" #&CDS_LOCATION = "C142" &SEC = "1" #&CDS_SEC = "1";
"1":   PN = "1"  !CDS_PN = "1";
"2":   PN = "2"  !CDS_PN = "2";
BODY = "CAPACITOR","I241": LOCATION = "C146" #&CDS_LOCATION = "C146" &SEC = "1" #&CDS_SEC = "1";
"1":   PN = "1"  !CDS_PN = "1";
"2":   PN = "2"  !CDS_PN = "2";
BODY = "CAPACITOR","I242": LOCATION = "C151" #&CDS_LOCATION = "C151" &SEC = "1" #&CDS_SEC = "1";
"1":   PN = "1"  !CDS_PN = "1";
"2":   PN = "2"  !CDS_PN = "2";
BODY = "CAPACITOR","I243": LOCATION = "C128" #&CDS_LOCATION = "C128" &SEC = "1" #&CDS_SEC = "1";
"1":   PN = "1"  !CDS_PN = "1";
"2":   PN = "2"  !CDS_PN = "2";
BODY = "CAPACITOR","I245": LOCATION = "C160" #&CDS_LOCATION = "C160" &SEC = "1" #&CDS_SEC = "1";
"1":   PN = "1"  !CDS_PN = "1";
"2":   PN = "2"  !CDS_PN = "2";
BODY = "CAPACITOR","I246": LOCATION = "C117" #&CDS_LOCATION = "C117" &SEC = "1" #&CDS_SEC = "1";
"1":   PN = "1"  !CDS_PN = "1";
"2":   PN = "2"  !CDS_PN = "2";
BODY = "CAPACITOR","I248": LOCATION = "C131" #&CDS_LOCATION = "C131" &SEC = "1" #&CDS_SEC = "1";
"1":   PN = "1"  !CDS_PN = "1";
"2":   PN = "2"  !CDS_PN = "2";
BODY = "CAPACITOR","I249": LOCATION = "C136" #&CDS_LOCATION = "C136" &SEC = "1" #&CDS_SEC = "1";
"1":   PN = "1"  !CDS_PN = "1";
"2":   PN = "2"  !CDS_PN = "2";
BODY = "CAPACITOR","I250": LOCATION = "C148" #&CDS_LOCATION = "C148" &SEC = "1" #&CDS_SEC = "1";
"1":   PN = "1"  !CDS_PN = "1";
"2":   PN = "2"  !CDS_PN = "2";
BODY = "CAPACITOR","I251": LOCATION = "C218" #&CDS_LOCATION = "C218" &SEC = "1" #&CDS_SEC = "1";
"1":   PN = "1"  !CDS_PN = "1";
"2":   PN = "2"  !CDS_PN = "2";
BODY = "CAPACITOR","I252": LOCATION = "C105" #&CDS_LOCATION = "C105" &SEC = "1" #&CDS_SEC = "1";
"1":   PN = "1"  !CDS_PN = "1";
"2":   PN = "2"  !CDS_PN = "2";
BODY = "CAPACITOR","I253": LOCATION = "C111" #&CDS_LOCATION = "C111" &SEC = "1" #&CDS_SEC = "1";
"1":   PN = "1"  !CDS_PN = "1";
"2":   PN = "2"  !CDS_PN = "2";
BODY = "CAPACITOR","I254": LOCATION = "C118" #&CDS_LOCATION = "C118" &SEC = "1" #&CDS_SEC = "1";
"1":   PN = "1"  !CDS_PN = "1";
"2":   PN = "2"  !CDS_PN = "2";
BODY = "CAPACITOR","I255": LOCATION = "C124" #&CDS_LOCATION = "C124" &SEC = "1" #&CDS_SEC = "1";
"1":   PN = "1"  !CDS_PN = "1";
"2":   PN = "2"  !CDS_PN = "2";
BODY = "CAPACITOR","I256": LOCATION = "C110" #&CDS_LOCATION = "C110" &SEC = "1" #&CDS_SEC = "1";
"1":   PN = "1"  !CDS_PN = "1";
"2":   PN = "2"  !CDS_PN = "2";
BODY = "CAPACITOR","I257": LOCATION = "C104" #&CDS_LOCATION = "C104" &SEC = "1" #&CDS_SEC = "1";
"1":   PN = "1"  !CDS_PN = "1";
"2":   PN = "2"  !CDS_PN = "2";
BODY = "CAPACITOR","I258": LOCATION = "C217" #&CDS_LOCATION = "C217" &SEC = "1" #&CDS_SEC = "1";
"1":   PN = "1"  !CDS_PN = "1";
"2":   PN = "2"  !CDS_PN = "2";
BODY = "CAPACITOR","I259": LOCATION = "C209" #&CDS_LOCATION = "C209" &SEC = "1" #&CDS_SEC = "1";
"1":   PN = "1"  !CDS_PN = "1";
"2":   PN = "2"  !CDS_PN = "2";
BODY = "CAPACITOR","I260": LOCATION = "C205" #&CDS_LOCATION = "C205" &SEC = "1" #&CDS_SEC = "1";
"1":   PN = "1"  !CDS_PN = "1";
"2":   PN = "2"  !CDS_PN = "2";
BODY = "CAPACITOR","I264": LOCATION = "C125" #&CDS_LOCATION = "C125" &SEC = "1" #&CDS_SEC = "1";
"1":   PN = "1"  !CDS_PN = "1";
"2":   PN = "2"  !CDS_PN = "2";
BODY = "CAPACITOR","I265": LOCATION = "C143" #&CDS_LOCATION = "C143" &SEC = "1" #&CDS_SEC = "1";
"1":   PN = "1"  !CDS_PN = "1";
"2":   PN = "2"  !CDS_PN = "2";
BODY = "CAPACITOR","I266": LOCATION = "C155" #&CDS_LOCATION = "C155" &SEC = "1" #&CDS_SEC = "1";
"1":   PN = "1"  !CDS_PN = "1";
"2":   PN = "2"  !CDS_PN = "2";
BODY = "CAPACITOR","I267": LOCATION = "C168" #&CDS_LOCATION = "C168" &SEC = "1" #&CDS_SEC = "1";
"1":   PN = "1"  !CDS_PN = "1";
"2":   PN = "2"  !CDS_PN = "2";
BODY = "CAPACITOR","I268": LOCATION = "C164" #&CDS_LOCATION = "C164" &SEC = "1" #&CDS_SEC = "1";
"1":   PN = "1"  !CDS_PN = "1";
"2":   PN = "2"  !CDS_PN = "2";
BODY = "CAPACITOR","I270": LOCATION = "C154" #&CDS_LOCATION = "C154" &SEC = "1" #&CDS_SEC = "1";
"1":   PN = "1"  !CDS_PN = "1";
"2":   PN = "2"  !CDS_PN = "2";
BODY = "CAPACITOR","I271": LOCATION = "C159" #&CDS_LOCATION = "C159" &SEC = "1" #&CDS_SEC = "1";
"1":   PN = "1"  !CDS_PN = "1";
"2":   PN = "2"  !CDS_PN = "2";
BODY = "CAPACITOR","I272": LOCATION = "C163" #&CDS_LOCATION = "C163" &SEC = "1" #&CDS_SEC = "1";
"1":   PN = "1"  !CDS_PN = "1";
"2":   PN = "2"  !CDS_PN = "2";
BODY = "CAPACITOR","I273": LOCATION = "C167" #&CDS_LOCATION = "C167" &SEC = "1" #&CDS_SEC = "1";
"1":   PN = "1"  !CDS_PN = "1";
"2":   PN = "2"  !CDS_PN = "2";
BODY = "CAPACITOR","I274": LOCATION = "C179" #&CDS_LOCATION = "C179" &SEC = "1" #&CDS_SEC = "1";
"1":   PN = "1"  !CDS_PN = "1";
"2":   PN = "2"  !CDS_PN = "2";
BODY = "CAPACITOR","I275": LOCATION = "C138" #&CDS_LOCATION = "C138" &SEC = "1" #&CDS_SEC = "1";
"1":   PN = "1"  !CDS_PN = "1";
"2":   PN = "2"  !CDS_PN = "2";
BODY = "CAPACITOR","I276": LOCATION = "C150" #&CDS_LOCATION = "C150" &SEC = "1" #&CDS_SEC = "1";
"1":   PN = "1"  !CDS_PN = "1";
"2":   PN = "2"  !CDS_PN = "2";
BODY = "CAPACITOR","I277": LOCATION = "C177" #&CDS_LOCATION = "C177" &SEC = "1" #&CDS_SEC = "1";
"1":   PN = "1"  !CDS_PN = "1";
"2":   PN = "2"  !CDS_PN = "2";
BODY = "CAPACITOR","I280": LOCATION = "C173" #&CDS_LOCATION = "C173" &SEC = "1" #&CDS_SEC = "1";
"1":   PN = "1"  !CDS_PN = "1";
"2":   PN = "2"  !CDS_PN = "2";
BODY = "CAPACITOR","I281": LOCATION = "C137" #&CDS_LOCATION = "C137" &SEC = "1" #&CDS_SEC = "1";
"1":   PN = "1"  !CDS_PN = "1";
"2":   PN = "2"  !CDS_PN = "2";
BODY = "CAPACITOR","I282": LOCATION = "C170" #&CDS_LOCATION = "C170" &SEC = "1" #&CDS_SEC = "1";
"1":   PN = "1"  !CDS_PN = "1";
"2":   PN = "2"  !CDS_PN = "2";
BODY = "CAPACITOR","I283": LOCATION = "C178" #&CDS_LOCATION = "C178" &SEC = "1" #&CDS_SEC = "1";
"1":   PN = "1"  !CDS_PN = "1";
"2":   PN = "2"  !CDS_PN = "2";
BODY = "CAPACITOR","I290": LOCATION = "C291" #&CDS_LOCATION = "C291" &SEC = "1" #&CDS_SEC = "1";
"1":   PN = "1"  !CDS_PN = "1";
"2":   PN = "2"  !CDS_PN = "2";
BODY = "CAPACITOR","I291": LOCATION = "C292" #&CDS_LOCATION = "C292" &SEC = "1" #&CDS_SEC = "1";
"1":   PN = "1"  !CDS_PN = "1";
"2":   PN = "2"  !CDS_PN = "2";
BODY = "CAPACITOR","I292": LOCATION = "C93" #&CDS_LOCATION = "C93" &SEC = "1" #&CDS_SEC = "1";
"1":   PN = "1"  !CDS_PN = "1";
"2":   PN = "2"  !CDS_PN = "2";
DRAWING = "@timecard_lib.timecard(sch_1):page522";
BODY = "CAPACITOR","I142": LOCATION = "C254" #&CDS_LOCATION = "C254" &SEC = "1" #&CDS_SEC = "1";
"1":   PN = "1"  !CDS_PN = "1";
"2":   PN = "2"  !CDS_PN = "2";
BODY = "CAPACITOR","I143": LOCATION = "C253" #&CDS_LOCATION = "C253" &SEC = "1" #&CDS_SEC = "1";
"1":   PN = "1"  !CDS_PN = "1";
"2":   PN = "2"  !CDS_PN = "2";
BODY = "OSC6P_V2","I144": LOCATION = "Y3" #&CDS_LOCATION = "Y3" &SEC = "1" #&CDS_SEC = "1";
"GND":   PN = "3"  !CDS_PN = "3";
"NC":   PN = "2"  !CDS_PN = "2";
"OE":   PN = "1"  !CDS_PN = "1";
"OUT_N":   PN = "5"  !CDS_PN = "5";
"OUT_P":   PN = "4"  !CDS_PN = "4";
"VDD":   PN = "6"  !CDS_PN = "6";
BODY = "OSC6P_V2","I145": LOCATION = "Y4" #&CDS_LOCATION = "Y4" &SEC = "1" #&CDS_SEC = "1";
"GND":   PN = "3"  !CDS_PN = "3";
"NC":   PN = "2"  !CDS_PN = "2";
"OE":   PN = "1"  !CDS_PN = "1";
"OUT_N":   PN = "5"  !CDS_PN = "5";
"OUT_P":   PN = "4"  !CDS_PN = "4";
"VDD":   PN = "6"  !CDS_PN = "6";
BODY = "FERRITEBEAD","I146": LOCATION = "L14" #&CDS_LOCATION = "L14" &SEC = "1" #&CDS_SEC = "1";
"1":   PN = "1"  !CDS_PN = "1";
"2":   PN = "2"  !CDS_PN = "2";
BODY = "CAPACITOR","I147": LOCATION = "C248" #&CDS_LOCATION = "C248" &SEC = "1" #&CDS_SEC = "1";
"1":   PN = "1"  !CDS_PN = "1";
"2":   PN = "2"  !CDS_PN = "2";
BODY = "RESISTOR","I149": LOCATION = "R235" #&CDS_LOCATION = "R235" &SEC = "1" #&CDS_SEC = "1";
"1":   PN = "1"  !CDS_PN = "1";
"2":   PN = "2"  !CDS_PN = "2";
BODY = "CAPACITOR","I151": LOCATION = "C246" #&CDS_LOCATION = "C246" &SEC = "1" #&CDS_SEC = "1";
"1":   PN = "1"  !CDS_PN = "1";
"2":   PN = "2"  !CDS_PN = "2";
BODY = "CAPACITOR","I152": LOCATION = "C244" #&CDS_LOCATION = "C244" &SEC = "1" #&CDS_SEC = "1";
"1":   PN = "1"  !CDS_PN = "1";
"2":   PN = "2"  !CDS_PN = "2";
BODY = "CAPACITOR","I153": LOCATION = "C245" #&CDS_LOCATION = "C245" &SEC = "1" #&CDS_SEC = "1";
"1":   PN = "1"  !CDS_PN = "1";
"2":   PN = "2"  !CDS_PN = "2";
BODY = "CAPACITOR","I154": LOCATION = "C247" #&CDS_LOCATION = "C247" &SEC = "1" #&CDS_SEC = "1";
"1":   PN = "1"  !CDS_PN = "1";
"2":   PN = "2"  !CDS_PN = "2";
BODY = "RESISTOR","I156": LOCATION = "R236" #&CDS_LOCATION = "R236" &SEC = "1" #&CDS_SEC = "1";
"1":   PN = "1"  !CDS_PN = "1";
"2":   PN = "2"  !CDS_PN = "2";
BODY = "CAPACITOR","I158": LOCATION = "C249" #&CDS_LOCATION = "C249" &SEC = "1" #&CDS_SEC = "1";
"1":   PN = "1"  !CDS_PN = "1";
"2":   PN = "2"  !CDS_PN = "2";
BODY = "FERRITEBEAD","I159": LOCATION = "L10" #&CDS_LOCATION = "L10" &SEC = "1" #&CDS_SEC = "1";
"1":   PN = "1"  !CDS_PN = "1";
"2":   PN = "2"  !CDS_PN = "2";
BODY = "CAPACITOR","I160": LOCATION = "C252" #&CDS_LOCATION = "C252" &SEC = "1" #&CDS_SEC = "1";
"1":   PN = "1"  !CDS_PN = "1";
"2":   PN = "2"  !CDS_PN = "2";
BODY = "CAPACITOR","I161": LOCATION = "C251" #&CDS_LOCATION = "C251" &SEC = "1" #&CDS_SEC = "1";
"1":   PN = "1"  !CDS_PN = "1";
"2":   PN = "2"  !CDS_PN = "2";
BODY = "RESISTOR","I169": LOCATION = "R239" #&CDS_LOCATION = "R239" &SEC = "1" #&CDS_SEC = "1";
"1":   PN = "1"  !CDS_PN = "1";
"2":   PN = "2"  !CDS_PN = "2";
BODY = "RESISTOR","I170": LOCATION = "R241" #&CDS_LOCATION = "R241" &SEC = "1" #&CDS_SEC = "1";
"1":   PN = "1"  !CDS_PN = "1";
"2":   PN = "2"  !CDS_PN = "2";
BODY = "RESISTOR","I172": LOCATION = "R240" #&CDS_LOCATION = "R240" &SEC = "1" #&CDS_SEC = "1";
"1":   PN = "1"  !CDS_PN = "1";
"2":   PN = "2"  !CDS_PN = "2";
BODY = "RESISTOR","I174": LOCATION = "R242" #&CDS_LOCATION = "R242" &SEC = "1" #&CDS_SEC = "1";
"1":   PN = "1"  !CDS_PN = "1";
"2":   PN = "2"  !CDS_PN = "2";
DRAWING = "@timecard_lib.timecard(sch_1):page33";
BODY = "MEC_MTH8","I1": LOCATION = "ME11" #&CDS_LOCATION = "ME11" &SEC = "1" #&CDS_SEC = "1";
"1":   PN = "1"  !CDS_PN = "1";
"2":   PN = "2"  !CDS_PN = "2";
"3":   PN = "3"  !CDS_PN = "3";
"4":   PN = "4"  !CDS_PN = "4";
"5":   PN = "5"  !CDS_PN = "5";
"6":   PN = "6"  !CDS_PN = "6";
"7":   PN = "7"  !CDS_PN = "7";
"8":   PN = "8"  !CDS_PN = "8";
BODY = "MEC_MTH8","I2": LOCATION = "ME12" #&CDS_LOCATION = "ME12" &SEC = "1" #&CDS_SEC = "1";
"1":   PN = "1"  !CDS_PN = "1";
"2":   PN = "2"  !CDS_PN = "2";
"3":   PN = "3"  !CDS_PN = "3";
"4":   PN = "4"  !CDS_PN = "4";
"5":   PN = "5"  !CDS_PN = "5";
"6":   PN = "6"  !CDS_PN = "6";
"7":   PN = "7"  !CDS_PN = "7";
"8":   PN = "8"  !CDS_PN = "8";
BODY = "MEC_MTH8","I5": LOCATION = "ME10" #&CDS_LOCATION = "ME10" &SEC = "1" #&CDS_SEC = "1";
"1":   PN = "1"  !CDS_PN = "1";
"2":   PN = "2"  !CDS_PN = "2";
"3":   PN = "3"  !CDS_PN = "3";
"4":   PN = "4"  !CDS_PN = "4";
"5":   PN = "5"  !CDS_PN = "5";
"6":   PN = "6"  !CDS_PN = "6";
"7":   PN = "7"  !CDS_PN = "7";
"8":   PN = "8"  !CDS_PN = "8";
BODY = "MEC_MTH8","I7": LOCATION = "ME9" #&CDS_LOCATION = "ME9" &SEC = "1" #&CDS_SEC = "1";
"1":   PN = "1"  !CDS_PN = "1";
"2":   PN = "2"  !CDS_PN = "2";
"3":   PN = "3"  !CDS_PN = "3";
"4":   PN = "4"  !CDS_PN = "4";
"5":   PN = "5"  !CDS_PN = "5";
"6":   PN = "6"  !CDS_PN = "6";
"7":   PN = "7"  !CDS_PN = "7";
"8":   PN = "8"  !CDS_PN = "8";
BODY = "NULL","I47": #LOCATION = "SP54" !CDS_LOCATION = "SP54";
BODY = "NULL","I48": #LOCATION = "SP55" !CDS_LOCATION = "SP55";
BODY = "NULL","I49": #LOCATION = "SP57" !CDS_LOCATION = "SP57";
BODY = "NULL","I50": #LOCATION = "SP56" !CDS_LOCATION = "SP56";
BODY = "NULL","I51": #LOCATION = "SP61" !CDS_LOCATION = "SP61";
BODY = "NULL","I52": #LOCATION = "SP60" !CDS_LOCATION = "SP60";
BODY = "NULL","I53": #LOCATION = "SP59" !CDS_LOCATION = "SP59";
BODY = "NULL","I54": #LOCATION = "SP58" !CDS_LOCATION = "SP58";
BODY = "NULL","I55": #LOCATION = "SP62" !CDS_LOCATION = "SP62";
BODY = "NULL","I56": #LOCATION = "SP63" !CDS_LOCATION = "SP63";
BODY = "NULL","I57": #LOCATION = "SP64" !CDS_LOCATION = "SP64";
BODY = "NULL","I58": #LOCATION = "SP65" !CDS_LOCATION = "SP65";
BODY = "NULL","I59": #LOCATION = "SP47" !CDS_LOCATION = "SP47";
BODY = "NULL","I60": #LOCATION = "SP48" !CDS_LOCATION = "SP48";
BODY = "NULL","I61": #LOCATION = "SP53" !CDS_LOCATION = "SP53";
BODY = "NULL","I62": #LOCATION = "SP52" !CDS_LOCATION = "SP52";
BODY = "NULL","I63": #LOCATION = "SP51" !CDS_LOCATION = "SP51";
BODY = "NULL","I64": #LOCATION = "SP50" !CDS_LOCATION = "SP50";
BODY = "NULL","I65": #LOCATION = "SP49" !CDS_LOCATION = "SP49";
BODY = "NULL","I66": #LOCATION = "SP46" !CDS_LOCATION = "SP46";
BODY = "NULL","I67": #LOCATION = "SP45" !CDS_LOCATION = "SP45";
BODY = "NULL","I68": #LOCATION = "SP44" !CDS_LOCATION = "SP44";
BODY = "NULL","I69": #LOCATION = "SP43" !CDS_LOCATION = "SP43";
BODY = "NULL","I70": #LOCATION = "SP42" !CDS_LOCATION = "SP42";
BODY = "NULL","I83": #LOCATION = "SP71" !CDS_LOCATION = "SP71";
BODY = "NULL","I84": #LOCATION = "SP70" !CDS_LOCATION = "SP70";
BODY = "NULL","I85": #LOCATION = "SP69" !CDS_LOCATION = "SP69";
BODY = "NULL","I89": #LOCATION = "SP68" !CDS_LOCATION = "SP68";
BODY = "NULL","I90": #LOCATION = "SP67" !CDS_LOCATION = "SP67";
BODY = "NULL","I93": #LOCATION = "SP66" !CDS_LOCATION = "SP66";
BODY = "MEC_NPTH","I120": LOCATION = "ME8" #&CDS_LOCATION = "ME8";
BODY = "MEC_NPTH","I121": LOCATION = "ME7" #&CDS_LOCATION = "ME7";
BODY = "MEC_NPTH","I122": LOCATION = "ME6" #&CDS_LOCATION = "ME6";
BODY = "MEC_NPTH","I123": LOCATION = "ME5" #&CDS_LOCATION = "ME5";
BODY = "NUT","I125": #LOCATION = "ME3" !CDS_LOCATION = "ME3" &SEC = "1" #&CDS_SEC = "1";
"1":   PN = "1"  !CDS_PN = "1";
BODY = "NUT","I126": #LOCATION = "ME4" !CDS_LOCATION = "ME4" &SEC = "1" #&CDS_SEC = "1";
"1":   PN = "1"  !CDS_PN = "1";
BODY = "NUT","I127": #LOCATION = "ME1" !CDS_LOCATION = "ME1" &SEC = "1" #&CDS_SEC = "1";
"1":   PN = "1"  !CDS_PN = "1";
BODY = "NUT","I129": #LOCATION = "ME2" !CDS_LOCATION = "ME2" &SEC = "1" #&CDS_SEC = "1";
"1":   PN = "1"  !CDS_PN = "1";
BODY = "SOLDER_PREFORM","I130": #LOCATION = "SP4" !CDS_LOCATION = "SP4" &SEC = "1" #&CDS_SEC = "1";
"1":   PN = "1"  !CDS_PN = "1";
"2":   PN = "2"  !CDS_PN = "2";
BODY = "SOLDER_PREFORM","I131": #LOCATION = "SP5" !CDS_LOCATION = "SP5" &SEC = "1" #&CDS_SEC = "1";
"1":   PN = "1"  !CDS_PN = "1";
"2":   PN = "2"  !CDS_PN = "2";
BODY = "SOLDER_PREFORM","I132": #LOCATION = "SP7" !CDS_LOCATION = "SP7" &SEC = "1" #&CDS_SEC = "1";
"1":   PN = "1"  !CDS_PN = "1";
"2":   PN = "2"  !CDS_PN = "2";
BODY = "SOLDER_PREFORM","I133": #LOCATION = "SP6" !CDS_LOCATION = "SP6" &SEC = "1" #&CDS_SEC = "1";
"1":   PN = "1"  !CDS_PN = "1";
"2":   PN = "2"  !CDS_PN = "2";
BODY = "SOLDER_PREFORM","I134": #LOCATION = "SP8" !CDS_LOCATION = "SP8" &SEC = "1" #&CDS_SEC = "1";
"1":   PN = "1"  !CDS_PN = "1";
"2":   PN = "2"  !CDS_PN = "2";
BODY = "SOLDER_PREFORM","I135": #LOCATION = "SP9" !CDS_LOCATION = "SP9" &SEC = "1" #&CDS_SEC = "1";
"1":   PN = "1"  !CDS_PN = "1";
"2":   PN = "2"  !CDS_PN = "2";
BODY = "SOLDER_PREFORM","I136": #LOCATION = "SP11" !CDS_LOCATION = "SP11" &SEC = "1" #&CDS_SEC = "1";
"1":   PN = "1"  !CDS_PN = "1";
"2":   PN = "2"  !CDS_PN = "2";
BODY = "SOLDER_PREFORM","I137": #LOCATION = "SP10" !CDS_LOCATION = "SP10" &SEC = "1" #&CDS_SEC = "1";
"1":   PN = "1"  !CDS_PN = "1";
"2":   PN = "2"  !CDS_PN = "2";
BODY = "SOLDER_PREFORM","I138": #LOCATION = "SP15" !CDS_LOCATION = "SP15" &SEC = "1" #&CDS_SEC = "1";
"1":   PN = "1"  !CDS_PN = "1";
"2":   PN = "2"  !CDS_PN = "2";
BODY = "SOLDER_PREFORM","I139": #LOCATION = "SP14" !CDS_LOCATION = "SP14" &SEC = "1" #&CDS_SEC = "1";
"1":   PN = "1"  !CDS_PN = "1";
"2":   PN = "2"  !CDS_PN = "2";
BODY = "SOLDER_PREFORM","I140": #LOCATION = "SP13" !CDS_LOCATION = "SP13" &SEC = "1" #&CDS_SEC = "1";
"1":   PN = "1"  !CDS_PN = "1";
"2":   PN = "2"  !CDS_PN = "2";
BODY = "SOLDER_PREFORM","I141": #LOCATION = "SP12" !CDS_LOCATION = "SP12" &SEC = "1" #&CDS_SEC = "1";
"1":   PN = "1"  !CDS_PN = "1";
"2":   PN = "2"  !CDS_PN = "2";
BODY = "SOLDER_PREFORM","I142": #LOCATION = "SP17" !CDS_LOCATION = "SP17" &SEC = "1" #&CDS_SEC = "1";
"1":   PN = "1"  !CDS_PN = "1";
"2":   PN = "2"  !CDS_PN = "2";
BODY = "SOLDER_PREFORM","I143": #LOCATION = "SP27" !CDS_LOCATION = "SP27" &SEC = "1" #&CDS_SEC = "1";
"1":   PN = "1"  !CDS_PN = "1";
"2":   PN = "2"  !CDS_PN = "2";
BODY = "SOLDER_PREFORM","I144": #LOCATION = "SP26" !CDS_LOCATION = "SP26" &SEC = "1" #&CDS_SEC = "1";
"1":   PN = "1"  !CDS_PN = "1";
"2":   PN = "2"  !CDS_PN = "2";
BODY = "SOLDER_PREFORM","I145": #LOCATION = "SP25" !CDS_LOCATION = "SP25" &SEC = "1" #&CDS_SEC = "1";
"1":   PN = "1"  !CDS_PN = "1";
"2":   PN = "2"  !CDS_PN = "2";
BODY = "SOLDER_PREFORM","I146": #LOCATION = "SP24" !CDS_LOCATION = "SP24" &SEC = "1" #&CDS_SEC = "1";
"1":   PN = "1"  !CDS_PN = "1";
"2":   PN = "2"  !CDS_PN = "2";
BODY = "SOLDER_PREFORM","I147": #LOCATION = "SP23" !CDS_LOCATION = "SP23" &SEC = "1" #&CDS_SEC = "1";
"1":   PN = "1"  !CDS_PN = "1";
"2":   PN = "2"  !CDS_PN = "2";
BODY = "SOLDER_PREFORM","I148": #LOCATION = "SP22" !CDS_LOCATION = "SP22" &SEC = "1" #&CDS_SEC = "1";
"1":   PN = "1"  !CDS_PN = "1";
"2":   PN = "2"  !CDS_PN = "2";
BODY = "SOLDER_PREFORM","I149": #LOCATION = "SP20" !CDS_LOCATION = "SP20" &SEC = "1" #&CDS_SEC = "1";
"1":   PN = "1"  !CDS_PN = "1";
"2":   PN = "2"  !CDS_PN = "2";
BODY = "SOLDER_PREFORM","I150": #LOCATION = "SP21" !CDS_LOCATION = "SP21" &SEC = "1" #&CDS_SEC = "1";
"1":   PN = "1"  !CDS_PN = "1";
"2":   PN = "2"  !CDS_PN = "2";
BODY = "SOLDER_PREFORM","I151": #LOCATION = "SP19" !CDS_LOCATION = "SP19" &SEC = "1" #&CDS_SEC = "1";
"1":   PN = "1"  !CDS_PN = "1";
"2":   PN = "2"  !CDS_PN = "2";
BODY = "SOLDER_PREFORM","I152": #LOCATION = "SP18" !CDS_LOCATION = "SP18" &SEC = "1" #&CDS_SEC = "1";
"1":   PN = "1"  !CDS_PN = "1";
"2":   PN = "2"  !CDS_PN = "2";
BODY = "SOLDER_PREFORM","I153": #LOCATION = "SP16" !CDS_LOCATION = "SP16" &SEC = "1" #&CDS_SEC = "1";
"1":   PN = "1"  !CDS_PN = "1";
"2":   PN = "2"  !CDS_PN = "2";
BODY = "SOLDER_PREFORM","I155": #LOCATION = "SP41" !CDS_LOCATION = "SP41" &SEC = "1" #&CDS_SEC = "1";
"1":   PN = "1"  !CDS_PN = "1";
"2":   PN = "2"  !CDS_PN = "2";
BODY = "SOLDER_PREFORM","I159": #LOCATION = "SP38" !CDS_LOCATION = "SP38" &SEC = "1" #&CDS_SEC = "1";
"1":   PN = "1"  !CDS_PN = "1";
"2":   PN = "2"  !CDS_PN = "2";
BODY = "SOLDER_PREFORM","I161": #LOCATION = "SP37" !CDS_LOCATION = "SP37" &SEC = "1" #&CDS_SEC = "1";
"1":   PN = "1"  !CDS_PN = "1";
"2":   PN = "2"  !CDS_PN = "2";
BODY = "SOLDER_PREFORM","I163": #LOCATION = "SP36" !CDS_LOCATION = "SP36" &SEC = "1" #&CDS_SEC = "1";
"1":   PN = "1"  !CDS_PN = "1";
"2":   PN = "2"  !CDS_PN = "2";
BODY = "SOLDER_PREFORM","I165": #LOCATION = "SP35" !CDS_LOCATION = "SP35" &SEC = "1" #&CDS_SEC = "1";
"1":   PN = "1"  !CDS_PN = "1";
"2":   PN = "2"  !CDS_PN = "2";
BODY = "SOLDER_PREFORM","I167": #LOCATION = "SP34" !CDS_LOCATION = "SP34" &SEC = "1" #&CDS_SEC = "1";
"1":   PN = "1"  !CDS_PN = "1";
"2":   PN = "2"  !CDS_PN = "2";
BODY = "SOLDER_PREFORM","I169": #LOCATION = "SP33" !CDS_LOCATION = "SP33" &SEC = "1" #&CDS_SEC = "1";
"1":   PN = "1"  !CDS_PN = "1";
"2":   PN = "2"  !CDS_PN = "2";
BODY = "SOLDER_PREFORM","I171": #LOCATION = "SP32" !CDS_LOCATION = "SP32" &SEC = "1" #&CDS_SEC = "1";
"1":   PN = "1"  !CDS_PN = "1";
"2":   PN = "2"  !CDS_PN = "2";
BODY = "SOLDER_PREFORM","I172": #LOCATION = "SP31" !CDS_LOCATION = "SP31" &SEC = "1" #&CDS_SEC = "1";
"1":   PN = "1"  !CDS_PN = "1";
"2":   PN = "2"  !CDS_PN = "2";
BODY = "SOLDER_PREFORM","I173": #LOCATION = "SP30" !CDS_LOCATION = "SP30" &SEC = "1" #&CDS_SEC = "1";
"1":   PN = "1"  !CDS_PN = "1";
"2":   PN = "2"  !CDS_PN = "2";
BODY = "SOLDER_PREFORM","I174": #LOCATION = "SP29" !CDS_LOCATION = "SP29" &SEC = "1" #&CDS_SEC = "1";
"1":   PN = "1"  !CDS_PN = "1";
"2":   PN = "2"  !CDS_PN = "2";
BODY = "SOLDER_PREFORM","I175": #LOCATION = "SP28" !CDS_LOCATION = "SP28" &SEC = "1" #&CDS_SEC = "1";
"1":   PN = "1"  !CDS_PN = "1";
"2":   PN = "2"  !CDS_PN = "2";
BODY = "SOLDER_PREFORM","I176": #LOCATION = "SP40" !CDS_LOCATION = "SP40" &SEC = "1" #&CDS_SEC = "1";
"1":   PN = "1"  !CDS_PN = "1";
"2":   PN = "2"  !CDS_PN = "2";
BODY = "SOLDER_PREFORM","I177": #LOCATION = "SP39" !CDS_LOCATION = "SP39" &SEC = "1" #&CDS_SEC = "1";
"1":   PN = "1"  !CDS_PN = "1";
"2":   PN = "2"  !CDS_PN = "2";
END.
